(kicad_sch
	(version 20250114)
	(generator "eeschema")
	(generator_version "9.0")
	(paper "A3")
	(title_block
		(title "PolarFire SoM")
		(date "2025-07-22")
		(rev "1.1.4")
		(company "Antmicro Ltd")
		(comment 1 "www.antmicro.com")
	)
	(text "To use SD card on baseboard\nset SD_PWR_ON to 3V3 on PF SoC"
		(exclude_from_sim no)
		(at 125.73 204.47 0)
		(effects
			(font
				(size 1.27 1.27)
			)
			(justify left bottom)
		)
	)
	(text "PolarFire Bank 4\nMSSIO"
		(exclude_from_sim no)
		(at 13.97 27.305 0)
		(effects
			(font
				(size 4 4)
				(thickness 0.8)
				(bold yes)
			)
			(justify left bottom)
		)
	)
	(text "PolarFire Bank 2\nMSSIO"
		(exclude_from_sim no)
		(at 212.09 27.305 0)
		(effects
			(font
				(size 4 4)
				(thickness 0.8)
				(bold yes)
			)
			(justify left bottom)
		)
	)
	(text "SD card"
		(exclude_from_sim no)
		(at 106.68 152.4 0)
		(effects
			(font
				(size 4 4)
				(thickness 0.8)
				(bold yes)
			)
			(justify left bottom)
		)
	)
	(text "eMMC"
		(exclude_from_sim no)
		(at 81.28 152.4 0)
		(effects
			(font
				(size 4 4)
				(thickness 0.8)
				(bold yes)
			)
			(justify left bottom)
		)
	)
	(text "Memory selection"
		(exclude_from_sim no)
		(at 79.375 140.335 0)
		(effects
			(font
				(size 4 4)
				(thickness 0.8)
				(bold yes)
			)
			(justify left bottom)
		)
	)
	(junction
		(at 289.56 185.42)
		(diameter 0)
		(color 0 0 0 0)
	)
	(junction
		(at 293.37 138.43)
		(diameter 0)
		(color 0 0 0 0)
	)
	(junction
		(at 307.34 208.28)
		(diameter 0)
		(color 0 0 0 0)
	)
	(junction
		(at 293.37 199.39)
		(diameter 0)
		(color 0 0 0 0)
	)
	(junction
		(at 284.48 196.85)
		(diameter 0)
		(color 0 0 0 0)
	)
	(junction
		(at 304.8 205.74)
		(diameter 0)
		(color 0 0 0 0)
	)
	(no_connect
		(at 123.19 189.23)
	)
	(no_connect
		(at 326.39 82.55)
	)
	(no_connect
		(at 326.39 92.71)
	)
	(no_connect
		(at 95.25 199.39)
	)
	(no_connect
		(at 121.92 81.28)
	)
	(no_connect
		(at 113.03 189.23)
	)
	(no_connect
		(at 326.39 69.85)
	)
	(no_connect
		(at 326.39 85.09)
	)
	(no_connect
		(at 121.92 83.82)
	)
	(no_connect
		(at 85.09 199.39)
	)
	(no_connect
		(at 326.39 77.47)
	)
	(no_connect
		(at 326.39 80.01)
	)
	(no_connect
		(at 326.39 72.39)
	)
	(bus_entry
		(at 135.89 180.34)
		(size 2.54 -2.54)
		(stroke
			(width 0)
			(type default)
		)
	)
	(bus_entry
		(at 135.89 166.37)
		(size 2.54 -2.54)
		(stroke
			(width 0)
			(type default)
		)
	)
	(bus_entry
		(at 72.39 180.34)
		(size -2.54 -2.54)
		(stroke
			(width 0)
			(type default)
		)
	)
	(bus_entry
		(at 271.78 72.39)
		(size 2.54 2.54)
		(stroke
			(width 0)
			(type default)
		)
	)
	(bus_entry
		(at 135.89 161.29)
		(size 2.54 -2.54)
		(stroke
			(width 0)
			(type default)
		)
	)
	(bus_entry
		(at 72.39 194.31)
		(size -2.54 -2.54)
		(stroke
			(width 0)
			(type default)
		)
	)
	(bus_entry
		(at 72.39 168.91)
		(size -2.54 -2.54)
		(stroke
			(width 0)
			(type default)
		)
	)
	(bus_entry
		(at 271.78 64.77)
		(size 2.54 2.54)
		(stroke
			(width 0)
			(type default)
		)
	)
	(bus_entry
		(at 336.55 140.97)
		(size 2.54 -2.54)
		(stroke
			(width 0)
			(type default)
		)
	)
	(bus_entry
		(at 135.89 175.26)
		(size 2.54 -2.54)
		(stroke
			(width 0)
			(type default)
		)
	)
	(bus_entry
		(at 72.39 163.83)
		(size -2.54 -2.54)
		(stroke
			(width 0)
			(type default)
		)
	)
	(bus_entry
		(at 135.89 191.77)
		(size 2.54 -2.54)
		(stroke
			(width 0)
			(type default)
		)
	)
	(bus_entry
		(at 334.01 214.63)
		(size -2.54 2.54)
		(stroke
			(width 0)
			(type default)
		)
	)
	(bus_entry
		(at 135.89 194.31)
		(size 2.54 -2.54)
		(stroke
			(width 0)
			(type default)
		)
	)
	(bus_entry
		(at 135.89 177.8)
		(size 2.54 -2.54)
		(stroke
			(width 0)
			(type default)
		)
	)
	(bus_entry
		(at 72.39 196.85)
		(size -2.54 -2.54)
		(stroke
			(width 0)
			(type default)
		)
	)
	(bus_entry
		(at 326.39 205.74)
		(size -2.54 2.54)
		(stroke
			(width 0)
			(type default)
		)
	)
	(bus_entry
		(at 135.89 68.58)
		(size 2.54 -2.54)
		(stroke
			(width 0)
			(type default)
		)
	)
	(bus_entry
		(at 135.89 172.72)
		(size 2.54 -2.54)
		(stroke
			(width 0)
			(type default)
		)
	)
	(bus_entry
		(at 271.78 82.55)
		(size 2.54 2.54)
		(stroke
			(width 0)
			(type default)
		)
	)
	(bus_entry
		(at 271.78 85.09)
		(size 2.54 2.54)
		(stroke
			(width 0)
			(type default)
		)
	)
	(bus_entry
		(at 72.39 175.26)
		(size -2.54 -2.54)
		(stroke
			(width 0)
			(type default)
		)
	)
	(bus_entry
		(at 271.78 90.17)
		(size 2.54 2.54)
		(stroke
			(width 0)
			(type default)
		)
	)
	(bus_entry
		(at 271.78 69.85)
		(size 2.54 2.54)
		(stroke
			(width 0)
			(type default)
		)
	)
	(bus_entry
		(at 271.78 62.23)
		(size 2.54 2.54)
		(stroke
			(width 0)
			(type default)
		)
	)
	(bus_entry
		(at 271.78 74.93)
		(size 2.54 2.54)
		(stroke
			(width 0)
			(type default)
		)
	)
	(bus_entry
		(at 334.01 212.09)
		(size -2.54 2.54)
		(stroke
			(width 0)
			(type default)
		)
	)
	(bus_entry
		(at 336.55 143.51)
		(size 2.54 -2.54)
		(stroke
			(width 0)
			(type default)
		)
	)
	(bus_entry
		(at 271.78 67.31)
		(size 2.54 2.54)
		(stroke
			(width 0)
			(type default)
		)
	)
	(bus_entry
		(at 271.78 87.63)
		(size 2.54 2.54)
		(stroke
			(width 0)
			(type default)
		)
	)
	(bus_entry
		(at 135.89 163.83)
		(size 2.54 -2.54)
		(stroke
			(width 0)
			(type default)
		)
	)
	(bus_entry
		(at 72.39 161.29)
		(size -2.54 -2.54)
		(stroke
			(width 0)
			(type default)
		)
	)
	(bus_entry
		(at 326.39 203.2)
		(size -2.54 2.54)
		(stroke
			(width 0)
			(type default)
		)
	)
	(bus_entry
		(at 271.78 80.01)
		(size 2.54 2.54)
		(stroke
			(width 0)
			(type default)
		)
	)
	(bus_entry
		(at 135.89 168.91)
		(size 2.54 -2.54)
		(stroke
			(width 0)
			(type default)
		)
	)
	(bus_entry
		(at 72.39 166.37)
		(size -2.54 -2.54)
		(stroke
			(width 0)
			(type default)
		)
	)
	(bus_entry
		(at 72.39 191.77)
		(size -2.54 -2.54)
		(stroke
			(width 0)
			(type default)
		)
	)
	(bus_entry
		(at 271.78 77.47)
		(size 2.54 2.54)
		(stroke
			(width 0)
			(type default)
		)
	)
	(bus_entry
		(at 72.39 172.72)
		(size -2.54 -2.54)
		(stroke
			(width 0)
			(type default)
		)
	)
	(bus_entry
		(at 72.39 177.8)
		(size -2.54 -2.54)
		(stroke
			(width 0)
			(type default)
		)
	)
	(bus
		(pts
			(xy 339.09 138.43) (xy 339.09 140.97)
		)
		(stroke
			(width 0)
			(type default)
		)
	)
	(wire
		(pts
			(xy 72.39 194.31) (xy 85.09 194.31)
		)
		(stroke
			(width 0)
			(type default)
		)
	)
	(bus
		(pts
			(xy 138.43 189.23) (xy 138.43 191.77)
		)
		(stroke
			(width 0)
			(type default)
		)
	)
	(wire
		(pts
			(xy 304.8 196.85) (xy 304.8 205.74)
		)
		(stroke
			(width 0)
			(type default)
		)
	)
	(wire
		(pts
			(xy 284.48 187.96) (xy 284.48 185.42)
		)
		(stroke
			(width 0)
			(type default)
		)
	)
	(wire
		(pts
			(xy 123.19 196.85) (xy 128.27 196.85)
		)
		(stroke
			(width 0)
			(type default)
		)
	)
	(wire
		(pts
			(xy 274.32 72.39) (xy 290.83 72.39)
		)
		(stroke
			(width 0)
			(type default)
		)
	)
	(bus
		(pts
			(xy 336.55 209.55) (xy 335.28 209.55)
		)
		(stroke
			(width 0)
			(type default)
		)
	)
	(wire
		(pts
			(xy 318.77 146.05) (xy 318.77 149.86)
		)
		(stroke
			(width 0)
			(type default)
		)
	)
	(bus
		(pts
			(xy 69.85 175.26) (xy 69.85 177.8)
		)
		(stroke
			(width 0)
			(type default)
		)
	)
	(bus
		(pts
			(xy 271.78 80.01) (xy 271.78 82.55)
		)
		(stroke
			(width 0)
			(type default)
		)
	)
	(wire
		(pts
			(xy 274.32 82.55) (xy 290.83 82.55)
		)
		(stroke
			(width 0)
			(type default)
		)
	)
	(bus
		(pts
			(xy 271.78 74.93) (xy 271.78 77.47)
		)
		(stroke
			(width 0)
			(type default)
		)
	)
	(wire
		(pts
			(xy 74.93 83.82) (xy 86.36 83.82)
		)
		(stroke
			(width 0)
			(type default)
		)
	)
	(bus
		(pts
			(xy 271.78 67.31) (xy 271.78 69.85)
		)
		(stroke
			(width 0)
			(type default)
		)
	)
	(wire
		(pts
			(xy 95.25 191.77) (xy 113.03 191.77)
		)
		(stroke
			(width 0)
			(type default)
		)
	)
	(wire
		(pts
			(xy 309.88 217.17) (xy 307.34 217.17)
		)
		(stroke
			(width 0)
			(type default)
		)
	)
	(wire
		(pts
			(xy 274.32 69.85) (xy 290.83 69.85)
		)
		(stroke
			(width 0)
			(type default)
		)
	)
	(wire
		(pts
			(xy 326.39 64.77) (xy 337.82 64.77)
		)
		(stroke
			(width 0)
			(type default)
		)
	)
	(bus
		(pts
			(xy 138.43 163.83) (xy 138.43 166.37)
		)
		(stroke
			(width 0)
			(type default)
		)
	)
	(wire
		(pts
			(xy 317.5 140.97) (xy 336.55 140.97)
		)
		(stroke
			(width 0)
			(type default)
		)
	)
	(wire
		(pts
			(xy 314.96 214.63) (xy 331.47 214.63)
		)
		(stroke
			(width 0)
			(type default)
		)
	)
	(polyline
		(pts
			(xy 210.185 13.335) (xy 210.185 283.845)
		)
		(stroke
			(width 0)
			(type dash)
		)
	)
	(bus
		(pts
			(xy 69.85 157.48) (xy 69.85 158.75)
		)
		(stroke
			(width 0)
			(type default)
		)
	)
	(wire
		(pts
			(xy 293.37 185.42) (xy 289.56 185.42)
		)
		(stroke
			(width 0)
			(type default)
		)
	)
	(wire
		(pts
			(xy 72.39 191.77) (xy 85.09 191.77)
		)
		(stroke
			(width 0)
			(type default)
		)
	)
	(wire
		(pts
			(xy 74.93 71.12) (xy 86.36 71.12)
		)
		(stroke
			(width 0)
			(type default)
		)
	)
	(bus
		(pts
			(xy 271.78 60.96) (xy 271.78 62.23)
		)
		(stroke
			(width 0)
			(type default)
		)
	)
	(wire
		(pts
			(xy 326.39 74.93) (xy 330.2 74.93)
		)
		(stroke
			(width 0)
			(type default)
		)
	)
	(wire
		(pts
			(xy 72.39 180.34) (xy 85.09 180.34)
		)
		(stroke
			(width 0)
			(type default)
		)
	)
	(wire
		(pts
			(xy 135.89 168.91) (xy 123.19 168.91)
		)
		(stroke
			(width 0)
			(type default)
		)
	)
	(wire
		(pts
			(xy 304.8 214.63) (xy 304.8 205.74)
		)
		(stroke
			(width 0)
			(type default)
		)
	)
	(wire
		(pts
			(xy 309.88 214.63) (xy 304.8 214.63)
		)
		(stroke
			(width 0)
			(type default)
		)
	)
	(wire
		(pts
			(xy 293.37 138.43) (xy 293.37 146.05)
		)
		(stroke
			(width 0)
			(type default)
		)
	)
	(wire
		(pts
			(xy 307.34 208.28) (xy 323.85 208.28)
		)
		(stroke
			(width 0)
			(type default)
		)
	)
	(wire
		(pts
			(xy 135.89 166.37) (xy 123.19 166.37)
		)
		(stroke
			(width 0)
			(type default)
		)
	)
	(wire
		(pts
			(xy 318.77 138.43) (xy 317.5 138.43)
		)
		(stroke
			(width 0)
			(type default)
		)
	)
	(bus
		(pts
			(xy 328.93 200.66) (xy 327.66 200.66)
		)
		(stroke
			(width 0)
			(type default)
		)
	)
	(wire
		(pts
			(xy 293.37 138.43) (xy 297.18 138.43)
		)
		(stroke
			(width 0)
			(type default)
		)
	)
	(wire
		(pts
			(xy 74.93 78.74) (xy 86.36 78.74)
		)
		(stroke
			(width 0)
			(type default)
		)
	)
	(bus
		(pts
			(xy 138.43 157.48) (xy 138.43 158.75)
		)
		(stroke
			(width 0)
			(type default)
		)
	)
	(bus
		(pts
			(xy 138.43 158.75) (xy 138.43 161.29)
		)
		(stroke
			(width 0)
			(type default)
		)
	)
	(bus
		(pts
			(xy 69.85 189.23) (xy 69.85 191.77)
		)
		(stroke
			(width 0)
			(type default)
		)
	)
	(wire
		(pts
			(xy 307.34 199.39) (xy 293.37 199.39)
		)
		(stroke
			(width 0)
			(type default)
		)
	)
	(bus
		(pts
			(xy 69.85 177.8) (xy 69.85 189.23)
		)
		(stroke
			(width 0)
			(type default)
		)
	)
	(wire
		(pts
			(xy 121.92 68.58) (xy 135.89 68.58)
		)
		(stroke
			(width 0)
			(type default)
		)
	)
	(wire
		(pts
			(xy 274.32 87.63) (xy 290.83 87.63)
		)
		(stroke
			(width 0)
			(type default)
		)
	)
	(bus
		(pts
			(xy 339.09 137.16) (xy 339.09 138.43)
		)
		(stroke
			(width 0)
			(type default)
		)
	)
	(wire
		(pts
			(xy 135.89 172.72) (xy 123.19 172.72)
		)
		(stroke
			(width 0)
			(type default)
		)
	)
	(wire
		(pts
			(xy 121.92 76.2) (xy 135.89 76.2)
		)
		(stroke
			(width 0)
			(type default)
		)
	)
	(wire
		(pts
			(xy 326.39 67.31) (xy 337.82 67.31)
		)
		(stroke
			(width 0)
			(type default)
		)
	)
	(bus
		(pts
			(xy 335.28 209.55) (xy 334.01 210.82)
		)
		(stroke
			(width 0)
			(type default)
		)
	)
	(bus
		(pts
			(xy 334.01 212.09) (xy 334.01 214.63)
		)
		(stroke
			(width 0)
			(type default)
		)
	)
	(wire
		(pts
			(xy 95.25 175.26) (xy 113.03 175.26)
		)
		(stroke
			(width 0)
			(type default)
		)
	)
	(wire
		(pts
			(xy 95.25 196.85) (xy 113.03 196.85)
		)
		(stroke
			(width 0)
			(type default)
		)
	)
	(wire
		(pts
			(xy 307.34 199.39) (xy 307.34 208.28)
		)
		(stroke
			(width 0)
			(type default)
		)
	)
	(wire
		(pts
			(xy 293.37 199.39) (xy 274.32 199.39)
		)
		(stroke
			(width 0)
			(type default)
		)
	)
	(wire
		(pts
			(xy 74.93 68.58) (xy 86.36 68.58)
		)
		(stroke
			(width 0)
			(type default)
		)
	)
	(wire
		(pts
			(xy 135.89 161.29) (xy 123.19 161.29)
		)
		(stroke
			(width 0)
			(type default)
		)
	)
	(bus
		(pts
			(xy 340.36 135.89) (xy 339.09 137.16)
		)
		(stroke
			(width 0)
			(type default)
		)
	)
	(bus
		(pts
			(xy 138.43 172.72) (xy 138.43 175.26)
		)
		(stroke
			(width 0)
			(type default)
		)
	)
	(wire
		(pts
			(xy 72.39 163.83) (xy 85.09 163.83)
		)
		(stroke
			(width 0)
			(type default)
		)
	)
	(wire
		(pts
			(xy 95.25 177.8) (xy 113.03 177.8)
		)
		(stroke
			(width 0)
			(type default)
		)
	)
	(bus
		(pts
			(xy 138.43 170.18) (xy 138.43 172.72)
		)
		(stroke
			(width 0)
			(type default)
		)
	)
	(wire
		(pts
			(xy 279.4 140.97) (xy 297.18 140.97)
		)
		(stroke
			(width 0)
			(type default)
		)
	)
	(bus
		(pts
			(xy 270.51 59.69) (xy 271.78 60.96)
		)
		(stroke
			(width 0)
			(type default)
		)
	)
	(wire
		(pts
			(xy 293.37 132.08) (xy 293.37 138.43)
		)
		(stroke
			(width 0)
			(type default)
		)
	)
	(bus
		(pts
			(xy 271.78 69.85) (xy 271.78 72.39)
		)
		(stroke
			(width 0)
			(type default)
		)
	)
	(bus
		(pts
			(xy 139.7 156.21) (xy 138.43 157.48)
		)
		(stroke
			(width 0)
			(type default)
		)
	)
	(wire
		(pts
			(xy 121.92 73.66) (xy 135.89 73.66)
		)
		(stroke
			(width 0)
			(type default)
		)
	)
	(wire
		(pts
			(xy 293.37 187.96) (xy 293.37 185.42)
		)
		(stroke
			(width 0)
			(type default)
		)
	)
	(wire
		(pts
			(xy 274.32 74.93) (xy 290.83 74.93)
		)
		(stroke
			(width 0)
			(type default)
		)
	)
	(wire
		(pts
			(xy 307.34 217.17) (xy 307.34 208.28)
		)
		(stroke
			(width 0)
			(type default)
		)
	)
	(wire
		(pts
			(xy 95.25 166.37) (xy 113.03 166.37)
		)
		(stroke
			(width 0)
			(type default)
		)
	)
	(wire
		(pts
			(xy 95.25 180.34) (xy 113.03 180.34)
		)
		(stroke
			(width 0)
			(type default)
		)
	)
	(wire
		(pts
			(xy 123.19 191.77) (xy 135.89 191.77)
		)
		(stroke
			(width 0)
			(type default)
		)
	)
	(bus
		(pts
			(xy 138.43 166.37) (xy 138.43 170.18)
		)
		(stroke
			(width 0)
			(type default)
		)
	)
	(bus
		(pts
			(xy 69.85 172.72) (xy 69.85 175.26)
		)
		(stroke
			(width 0)
			(type default)
		)
	)
	(wire
		(pts
			(xy 135.89 180.34) (xy 123.19 180.34)
		)
		(stroke
			(width 0)
			(type default)
		)
	)
	(wire
		(pts
			(xy 72.39 172.72) (xy 85.09 172.72)
		)
		(stroke
			(width 0)
			(type default)
		)
	)
	(bus
		(pts
			(xy 138.43 64.77) (xy 138.43 66.04)
		)
		(stroke
			(width 0)
			(type default)
		)
	)
	(wire
		(pts
			(xy 314.96 217.17) (xy 331.47 217.17)
		)
		(stroke
			(width 0)
			(type default)
		)
	)
	(bus
		(pts
			(xy 68.58 156.21) (xy 69.85 157.48)
		)
		(stroke
			(width 0)
			(type default)
		)
	)
	(wire
		(pts
			(xy 274.32 90.17) (xy 290.83 90.17)
		)
		(stroke
			(width 0)
			(type default)
		)
	)
	(wire
		(pts
			(xy 95.25 161.29) (xy 113.03 161.29)
		)
		(stroke
			(width 0)
			(type default)
		)
	)
	(wire
		(pts
			(xy 74.93 76.2) (xy 86.36 76.2)
		)
		(stroke
			(width 0)
			(type default)
		)
	)
	(wire
		(pts
			(xy 284.48 193.04) (xy 284.48 196.85)
		)
		(stroke
			(width 0)
			(type default)
		)
	)
	(wire
		(pts
			(xy 135.89 175.26) (xy 123.19 175.26)
		)
		(stroke
			(width 0)
			(type default)
		)
	)
	(bus
		(pts
			(xy 327.66 200.66) (xy 326.39 201.93)
		)
		(stroke
			(width 0)
			(type default)
		)
	)
	(bus
		(pts
			(xy 334.01 210.82) (xy 334.01 212.09)
		)
		(stroke
			(width 0)
			(type default)
		)
	)
	(wire
		(pts
			(xy 95.25 172.72) (xy 113.03 172.72)
		)
		(stroke
			(width 0)
			(type default)
		)
	)
	(wire
		(pts
			(xy 121.92 71.12) (xy 135.89 71.12)
		)
		(stroke
			(width 0)
			(type default)
		)
	)
	(wire
		(pts
			(xy 274.32 196.85) (xy 284.48 196.85)
		)
		(stroke
			(width 0)
			(type default)
		)
	)
	(wire
		(pts
			(xy 95.25 168.91) (xy 113.03 168.91)
		)
		(stroke
			(width 0)
			(type default)
		)
	)
	(wire
		(pts
			(xy 304.8 205.74) (xy 323.85 205.74)
		)
		(stroke
			(width 0)
			(type default)
		)
	)
	(wire
		(pts
			(xy 317.5 143.51) (xy 336.55 143.51)
		)
		(stroke
			(width 0)
			(type default)
		)
	)
	(wire
		(pts
			(xy 318.77 132.08) (xy 318.77 138.43)
		)
		(stroke
			(width 0)
			(type default)
		)
	)
	(bus
		(pts
			(xy 269.24 59.69) (xy 270.51 59.69)
		)
		(stroke
			(width 0)
			(type default)
		)
	)
	(bus
		(pts
			(xy 68.58 156.21) (xy 67.31 156.21)
		)
		(stroke
			(width 0)
			(type default)
		)
	)
	(bus
		(pts
			(xy 139.7 156.21) (xy 140.97 156.21)
		)
		(stroke
			(width 0)
			(type default)
		)
	)
	(wire
		(pts
			(xy 274.32 77.47) (xy 290.83 77.47)
		)
		(stroke
			(width 0)
			(type default)
		)
	)
	(bus
		(pts
			(xy 139.7 63.5) (xy 138.43 64.77)
		)
		(stroke
			(width 0)
			(type default)
		)
	)
	(wire
		(pts
			(xy 274.32 92.71) (xy 290.83 92.71)
		)
		(stroke
			(width 0)
			(type default)
		)
	)
	(wire
		(pts
			(xy 274.32 64.77) (xy 290.83 64.77)
		)
		(stroke
			(width 0)
			(type default)
		)
	)
	(wire
		(pts
			(xy 72.39 175.26) (xy 85.09 175.26)
		)
		(stroke
			(width 0)
			(type default)
		)
	)
	(bus
		(pts
			(xy 138.43 175.26) (xy 138.43 177.8)
		)
		(stroke
			(width 0)
			(type default)
		)
	)
	(wire
		(pts
			(xy 274.32 85.09) (xy 290.83 85.09)
		)
		(stroke
			(width 0)
			(type default)
		)
	)
	(wire
		(pts
			(xy 340.36 90.17) (xy 363.22 90.17)
		)
		(stroke
			(width 0)
			(type default)
		)
	)
	(bus
		(pts
			(xy 138.43 161.29) (xy 138.43 163.83)
		)
		(stroke
			(width 0)
			(type default)
		)
	)
	(bus
		(pts
			(xy 69.85 166.37) (xy 69.85 170.18)
		)
		(stroke
			(width 0)
			(type default)
		)
	)
	(wire
		(pts
			(xy 121.92 78.74) (xy 135.89 78.74)
		)
		(stroke
			(width 0)
			(type default)
		)
	)
	(wire
		(pts
			(xy 340.36 87.63) (xy 363.22 87.63)
		)
		(stroke
			(width 0)
			(type default)
		)
	)
	(wire
		(pts
			(xy 326.39 87.63) (xy 335.28 87.63)
		)
		(stroke
			(width 0)
			(type default)
		)
	)
	(wire
		(pts
			(xy 72.39 161.29) (xy 85.09 161.29)
		)
		(stroke
			(width 0)
			(type default)
		)
	)
	(bus
		(pts
			(xy 69.85 161.29) (xy 69.85 163.83)
		)
		(stroke
			(width 0)
			(type default)
		)
	)
	(wire
		(pts
			(xy 74.93 73.66) (xy 86.36 73.66)
		)
		(stroke
			(width 0)
			(type default)
		)
	)
	(wire
		(pts
			(xy 135.89 177.8) (xy 123.19 177.8)
		)
		(stroke
			(width 0)
			(type default)
		)
	)
	(bus
		(pts
			(xy 271.78 82.55) (xy 271.78 85.09)
		)
		(stroke
			(width 0)
			(type default)
		)
	)
	(wire
		(pts
			(xy 123.19 194.31) (xy 135.89 194.31)
		)
		(stroke
			(width 0)
			(type default)
		)
	)
	(wire
		(pts
			(xy 274.32 80.01) (xy 290.83 80.01)
		)
		(stroke
			(width 0)
			(type default)
		)
	)
	(wire
		(pts
			(xy 72.39 177.8) (xy 85.09 177.8)
		)
		(stroke
			(width 0)
			(type default)
		)
	)
	(bus
		(pts
			(xy 69.85 170.18) (xy 69.85 172.72)
		)
		(stroke
			(width 0)
			(type default)
		)
	)
	(bus
		(pts
			(xy 271.78 64.77) (xy 271.78 67.31)
		)
		(stroke
			(width 0)
			(type default)
		)
	)
	(wire
		(pts
			(xy 289.56 185.42) (xy 289.56 181.61)
		)
		(stroke
			(width 0)
			(type default)
		)
	)
	(wire
		(pts
			(xy 293.37 193.04) (xy 293.37 199.39)
		)
		(stroke
			(width 0)
			(type default)
		)
	)
	(bus
		(pts
			(xy 139.7 63.5) (xy 140.97 63.5)
		)
		(stroke
			(width 0)
			(type default)
		)
	)
	(wire
		(pts
			(xy 72.39 196.85) (xy 85.09 196.85)
		)
		(stroke
			(width 0)
			(type default)
		)
	)
	(wire
		(pts
			(xy 279.4 143.51) (xy 297.18 143.51)
		)
		(stroke
			(width 0)
			(type default)
		)
	)
	(wire
		(pts
			(xy 95.25 163.83) (xy 113.03 163.83)
		)
		(stroke
			(width 0)
			(type default)
		)
	)
	(bus
		(pts
			(xy 69.85 163.83) (xy 69.85 166.37)
		)
		(stroke
			(width 0)
			(type default)
		)
	)
	(bus
		(pts
			(xy 340.36 135.89) (xy 341.63 135.89)
		)
		(stroke
			(width 0)
			(type default)
		)
	)
	(wire
		(pts
			(xy 74.93 81.28) (xy 86.36 81.28)
		)
		(stroke
			(width 0)
			(type default)
		)
	)
	(bus
		(pts
			(xy 271.78 72.39) (xy 271.78 74.93)
		)
		(stroke
			(width 0)
			(type default)
		)
	)
	(wire
		(pts
			(xy 135.89 163.83) (xy 123.19 163.83)
		)
		(stroke
			(width 0)
			(type default)
		)
	)
	(bus
		(pts
			(xy 69.85 158.75) (xy 69.85 161.29)
		)
		(stroke
			(width 0)
			(type default)
		)
	)
	(wire
		(pts
			(xy 297.18 146.05) (xy 293.37 146.05)
		)
		(stroke
			(width 0)
			(type default)
		)
	)
	(wire
		(pts
			(xy 95.25 194.31) (xy 113.03 194.31)
		)
		(stroke
			(width 0)
			(type default)
		)
	)
	(bus
		(pts
			(xy 271.78 77.47) (xy 271.78 80.01)
		)
		(stroke
			(width 0)
			(type default)
		)
	)
	(wire
		(pts
			(xy 284.48 185.42) (xy 289.56 185.42)
		)
		(stroke
			(width 0)
			(type default)
		)
	)
	(wire
		(pts
			(xy 326.39 90.17) (xy 335.28 90.17)
		)
		(stroke
			(width 0)
			(type default)
		)
	)
	(wire
		(pts
			(xy 284.48 196.85) (xy 304.8 196.85)
		)
		(stroke
			(width 0)
			(type default)
		)
	)
	(bus
		(pts
			(xy 271.78 85.09) (xy 271.78 87.63)
		)
		(stroke
			(width 0)
			(type default)
		)
	)
	(bus
		(pts
			(xy 138.43 177.8) (xy 138.43 189.23)
		)
		(stroke
			(width 0)
			(type default)
		)
	)
	(wire
		(pts
			(xy 72.39 166.37) (xy 85.09 166.37)
		)
		(stroke
			(width 0)
			(type default)
		)
	)
	(bus
		(pts
			(xy 271.78 62.23) (xy 271.78 64.77)
		)
		(stroke
			(width 0)
			(type default)
		)
	)
	(wire
		(pts
			(xy 274.32 67.31) (xy 290.83 67.31)
		)
		(stroke
			(width 0)
			(type default)
		)
	)
	(wire
		(pts
			(xy 318.77 146.05) (xy 317.5 146.05)
		)
		(stroke
			(width 0)
			(type default)
		)
	)
	(bus
		(pts
			(xy 271.78 87.63) (xy 271.78 90.17)
		)
		(stroke
			(width 0)
			(type default)
		)
	)
	(bus
		(pts
			(xy 326.39 201.93) (xy 326.39 203.2)
		)
		(stroke
			(width 0)
			(type default)
		)
	)
	(bus
		(pts
			(xy 69.85 191.77) (xy 69.85 194.31)
		)
		(stroke
			(width 0)
			(type default)
		)
	)
	(bus
		(pts
			(xy 326.39 203.2) (xy 326.39 205.74)
		)
		(stroke
			(width 0)
			(type default)
		)
	)
	(wire
		(pts
			(xy 72.39 168.91) (xy 85.09 168.91)
		)
		(stroke
			(width 0)
			(type default)
		)
	)
	(label "ULPI.DATA5"
		(at 274.32 87.63 0)
		(effects
			(font
				(size 1.27 1.27)
			)
			(justify left bottom)
		)
	)
	(label "MEM.CLK"
		(at 109.22 191.77 180)
		(effects
			(font
				(size 1.27 1.27)
			)
			(justify right bottom)
		)
	)
	(label "I2C_SCL"
		(at 274.32 196.85 0)
		(effects
			(font
				(size 1.27 1.27)
			)
			(justify left bottom)
		)
	)
	(label "I2C_SDA"
		(at 274.32 199.39 0)
		(effects
			(font
				(size 1.27 1.27)
			)
			(justify left bottom)
		)
	)
	(label "ULPI.DATA6"
		(at 274.32 90.17 0)
		(effects
			(font
				(size 1.27 1.27)
			)
			(justify left bottom)
		)
	)
	(label "I2C_SDA"
		(at 337.82 67.31 180)
		(effects
			(font
				(size 1.27 1.27)
			)
			(justify right bottom)
		)
	)
	(label "MEM.DAT4"
		(at 109.22 180.34 180)
		(effects
			(font
				(size 1.27 1.27)
			)
			(justify right bottom)
		)
	)
	(label "MEM.DAT2"
		(at 109.22 175.26 180)
		(effects
			(font
				(size 1.27 1.27)
			)
			(justify right bottom)
		)
	)
	(label "PF_BT.RX"
		(at 336.55 143.51 180)
		(effects
			(font
				(size 1.27 1.27)
			)
			(justify right bottom)
		)
	)
	(label "MEM.DAT3"
		(at 74.93 81.28 0)
		(effects
			(font
				(size 1.27 1.27)
			)
			(justify left bottom)
		)
	)
	(label "SD.DAT2"
		(at 135.89 175.26 180)
		(effects
			(font
				(size 1.27 1.27)
			)
			(justify right bottom)
		)
	)
	(label "MEM.DAT3"
		(at 109.22 161.29 180)
		(effects
			(font
				(size 1.27 1.27)
			)
			(justify right bottom)
		)
	)
	(label "MEM.DAT4"
		(at 135.89 71.12 180)
		(effects
			(font
				(size 1.27 1.27)
			)
			(justify right bottom)
		)
	)
	(label "MEM.DAT5"
		(at 109.22 166.37 180)
		(effects
			(font
				(size 1.27 1.27)
			)
			(justify right bottom)
		)
	)
	(label "EMMC.DAT4"
		(at 72.39 180.34 0)
		(effects
			(font
				(size 1.27 1.27)
			)
			(justify left bottom)
		)
	)
	(label "EMMC.DAT0"
		(at 72.39 163.83 0)
		(effects
			(font
				(size 1.27 1.27)
			)
			(justify left bottom)
		)
	)
	(label "EMMC.DAT1"
		(at 72.39 172.72 0)
		(effects
			(font
				(size 1.27 1.27)
			)
			(justify left bottom)
		)
	)
	(label "ULPI.DATA0"
		(at 274.32 74.93 0)
		(effects
			(font
				(size 1.27 1.27)
			)
			(justify left bottom)
		)
	)
	(label "ULPI.DIR"
		(at 274.32 67.31 0)
		(effects
			(font
				(size 1.27 1.27)
			)
			(justify left bottom)
		)
	)
	(label "MEM.CMD"
		(at 74.93 71.12 0)
		(effects
			(font
				(size 1.27 1.27)
			)
			(justify left bottom)
		)
	)
	(label "ID.SDA"
		(at 316.865 217.17 0)
		(effects
			(font
				(size 1.27 1.27)
			)
			(justify left bottom)
		)
	)
	(label "BT_UART_TX"
		(at 279.4 140.97 0)
		(effects
			(font
				(size 1.27 1.27)
			)
			(justify left bottom)
		)
	)
	(label "SUPPLY.SCL"
		(at 309.245 205.74 0)
		(effects
			(font
				(size 1.27 1.27)
			)
			(justify left bottom)
		)
	)
	(label "EMMC.DAT2"
		(at 72.39 175.26 0)
		(effects
			(font
				(size 1.27 1.27)
			)
			(justify left bottom)
		)
	)
	(label "ULPI.DATA3"
		(at 274.32 82.55 0)
		(effects
			(font
				(size 1.27 1.27)
			)
			(justify left bottom)
		)
	)
	(label "SD.DAT1"
		(at 135.89 172.72 180)
		(effects
			(font
				(size 1.27 1.27)
			)
			(justify right bottom)
		)
	)
	(label "EMMC.DAT6"
		(at 72.39 177.8 0)
		(effects
			(font
				(size 1.27 1.27)
			)
			(justify left bottom)
		)
	)
	(label "MEM.CLK"
		(at 74.93 68.58 0)
		(effects
			(font
				(size 1.27 1.27)
			)
			(justify left bottom)
		)
	)
	(label "SD.CLK"
		(at 135.89 191.77 180)
		(effects
			(font
				(size 1.27 1.27)
			)
			(justify right bottom)
		)
	)
	(label "SD.DAT5"
		(at 135.89 166.37 180)
		(effects
			(font
				(size 1.27 1.27)
			)
			(justify right bottom)
		)
	)
	(label "SUPPLY.SDA"
		(at 309.245 208.28 0)
		(effects
			(font
				(size 1.27 1.27)
			)
			(justify left bottom)
		)
	)
	(label "ULPI.DATA7"
		(at 274.32 92.71 0)
		(effects
			(font
				(size 1.27 1.27)
			)
			(justify left bottom)
		)
	)
	(label "MEM.DAT0"
		(at 74.93 73.66 0)
		(effects
			(font
				(size 1.27 1.27)
			)
			(justify left bottom)
		)
	)
	(label "MEM.DAT6"
		(at 109.22 177.8 180)
		(effects
			(font
				(size 1.27 1.27)
			)
			(justify right bottom)
		)
	)
	(label "EMMC.DAT7"
		(at 72.39 168.91 0)
		(effects
			(font
				(size 1.27 1.27)
			)
			(justify left bottom)
		)
	)
	(label "EMMC.CMD"
		(at 72.39 194.31 0)
		(effects
			(font
				(size 1.27 1.27)
			)
			(justify left bottom)
		)
	)
	(label "ULPI.NXT"
		(at 274.32 69.85 0)
		(effects
			(font
				(size 1.27 1.27)
			)
			(justify left bottom)
		)
	)
	(label "MEM.DAT6"
		(at 135.89 76.2 180)
		(effects
			(font
				(size 1.27 1.27)
			)
			(justify right bottom)
		)
	)
	(label "PF_BT.TX"
		(at 336.55 140.97 180)
		(effects
			(font
				(size 1.27 1.27)
			)
			(justify right bottom)
		)
	)
	(label "ULPI.DATA2"
		(at 274.32 80.01 0)
		(effects
			(font
				(size 1.27 1.27)
			)
			(justify left bottom)
		)
	)
	(label "MEM.STRB"
		(at 74.93 83.82 0)
		(effects
			(font
				(size 1.27 1.27)
			)
			(justify left bottom)
		)
	)
	(label "MEM.DAT7"
		(at 135.89 78.74 180)
		(effects
			(font
				(size 1.27 1.27)
			)
			(justify right bottom)
		)
	)
	(label "ID.SCL"
		(at 316.865 214.63 0)
		(effects
			(font
				(size 1.27 1.27)
			)
			(justify left bottom)
		)
	)
	(label "I2C_SCL"
		(at 337.82 64.77 180)
		(effects
			(font
				(size 1.27 1.27)
			)
			(justify right bottom)
		)
	)
	(label "BT_UART_RX"
		(at 363.22 90.17 180)
		(effects
			(font
				(size 1.27 1.27)
			)
			(justify right bottom)
		)
	)
	(label "MEM.DAT7"
		(at 109.22 168.91 180)
		(effects
			(font
				(size 1.27 1.27)
			)
			(justify right bottom)
		)
	)
	(label "MEM.CMD"
		(at 109.22 194.31 180)
		(effects
			(font
				(size 1.27 1.27)
			)
			(justify right bottom)
		)
	)
	(label "SD.CMD"
		(at 135.89 194.31 180)
		(effects
			(font
				(size 1.27 1.27)
			)
			(justify right bottom)
		)
	)
	(label "EMMC.STRB"
		(at 72.39 196.85 0)
		(effects
			(font
				(size 1.27 1.27)
			)
			(justify left bottom)
		)
	)
	(label "EMMC.DAT5"
		(at 72.39 166.37 0)
		(effects
			(font
				(size 1.27 1.27)
			)
			(justify left bottom)
		)
	)
	(label "MEM.DAT5"
		(at 135.89 73.66 180)
		(effects
			(font
				(size 1.27 1.27)
			)
			(justify right bottom)
		)
	)
	(label "EMMC.RST_n"
		(at 135.89 68.58 180)
		(effects
			(font
				(size 1.27 1.27)
			)
			(justify right bottom)
		)
	)
	(label "EMMC.CLK"
		(at 72.39 191.77 0)
		(effects
			(font
				(size 1.27 1.27)
			)
			(justify left bottom)
		)
	)
	(label "BT_UART_RX"
		(at 279.4 143.51 0)
		(effects
			(font
				(size 1.27 1.27)
			)
			(justify left bottom)
		)
	)
	(label "BT_UART_TX"
		(at 363.22 87.63 180)
		(effects
			(font
				(size 1.27 1.27)
			)
			(justify right bottom)
		)
	)
	(label "SD.DAT6"
		(at 135.89 177.8 180)
		(effects
			(font
				(size 1.27 1.27)
			)
			(justify right bottom)
		)
	)
	(label "SD.DAT3"
		(at 135.89 161.29 180)
		(effects
			(font
				(size 1.27 1.27)
			)
			(justify right bottom)
		)
	)
	(label "MEM.DAT1"
		(at 74.93 76.2 0)
		(effects
			(font
				(size 1.27 1.27)
			)
			(justify left bottom)
		)
	)
	(label "SD.DAT7"
		(at 135.89 168.91 180)
		(effects
			(font
				(size 1.27 1.27)
			)
			(justify right bottom)
		)
	)
	(label "ULPI.DATA4"
		(at 274.32 85.09 0)
		(effects
			(font
				(size 1.27 1.27)
			)
			(justify left bottom)
		)
	)
	(label "ULPI.DATA1"
		(at 274.32 77.47 0)
		(effects
			(font
				(size 1.27 1.27)
			)
			(justify left bottom)
		)
	)
	(label "MEM.STRB"
		(at 109.22 196.85 180)
		(effects
			(font
				(size 1.27 1.27)
			)
			(justify right bottom)
		)
	)
	(label "ULPI.CLK"
		(at 274.32 64.77 0)
		(effects
			(font
				(size 1.27 1.27)
			)
			(justify left bottom)
		)
	)
	(label "ULPI.STP"
		(at 274.32 72.39 0)
		(effects
			(font
				(size 1.27 1.27)
			)
			(justify left bottom)
		)
	)
	(label "MEM.DAT1"
		(at 109.22 172.72 180)
		(effects
			(font
				(size 1.27 1.27)
			)
			(justify right bottom)
		)
	)
	(label "MEM.DAT0"
		(at 109.22 163.83 180)
		(effects
			(font
				(size 1.27 1.27)
			)
			(justify right bottom)
		)
	)
	(label "EMMC.DAT3"
		(at 72.39 161.29 0)
		(effects
			(font
				(size 1.27 1.27)
			)
			(justify left bottom)
		)
	)
	(label "SD.DAT4"
		(at 135.89 180.34 180)
		(effects
			(font
				(size 1.27 1.27)
			)
			(justify right bottom)
		)
	)
	(label "MEM.DAT2"
		(at 74.93 78.74 0)
		(effects
			(font
				(size 1.27 1.27)
			)
			(justify left bottom)
		)
	)
	(label "SD.DAT0"
		(at 135.89 163.83 180)
		(effects
			(font
				(size 1.27 1.27)
			)
			(justify right bottom)
		)
	)
	(global_label "PAC1934_SLOW"
		(shape input)
		(at 330.2 74.93 0)
		(fields_autoplaced yes)
		(effects
			(font
				(size 1.27 1.27)
			)
			(justify left)
		)
		(property "Intersheetrefs" "${INTERSHEET_REFS}"
			(at 347.0669 74.8506 0)
			(effects
				(font
					(size 1.27 1.27)
				)
				(justify left)
			)
		)
	)
	(global_label "SD_PWR_ON"
		(shape input)
		(at 128.27 196.85 0)
		(fields_autoplaced yes)
		(effects
			(font
				(size 1.27 1.27)
			)
			(justify left)
		)
		(property "Intersheetrefs" "${INTERSHEET_REFS}"
			(at 141.7502 196.7706 0)
			(effects
				(font
					(size 1.27 1.27)
				)
				(justify left)
			)
		)
	)
	(hierarchical_label "ID{I^{2}C}"
		(shape input)
		(at 336.55 209.55 0)
		(effects
			(font
				(size 1.27 1.27)
			)
			(justify left)
		)
	)
	(hierarchical_label "EMMC{SDIO}"
		(shape input)
		(at 67.31 156.21 180)
		(effects
			(font
				(size 1.27 1.27)
			)
			(justify right)
		)
	)
	(hierarchical_label "ULPI{ULPI}"
		(shape input)
		(at 269.24 59.69 180)
		(effects
			(font
				(size 1.27 1.27)
			)
			(justify right)
		)
	)
	(hierarchical_label "PF_BT{UART}"
		(shape input)
		(at 341.63 135.89 0)
		(effects
			(font
				(size 1.27 1.27)
			)
			(justify left)
		)
	)
	(hierarchical_label "SUPPLY{I^{2}C}"
		(shape input)
		(at 328.93 200.66 0)
		(effects
			(font
				(size 1.27 1.27)
			)
			(justify left)
		)
	)
	(hierarchical_label "SD{SDIO}"
		(shape input)
		(at 140.97 156.21 0)
		(effects
			(font
				(size 1.27 1.27)
			)
			(justify left)
		)
	)
	(hierarchical_label "EMMC{SDIO}"
		(shape input)
		(at 140.97 63.5 0)
		(effects
			(font
				(size 1.27 1.27)
			)
			(justify left)
		)
	)
	(symbol
		(lib_id "antmicroResistorNetworksArrays:R_4x0R_0201_array")
		(at 85.09 191.77 0)
		(unit 1)
		(exclude_from_sim no)
		(in_bom yes)
		(on_board yes)
		(dnp no)
		(property "Reference" "R24"
			(at 90.17 201.93 0)
			(effects
				(font
					(size 1.27 1.27)
					(thickness 0.15)
				)
			)
		)
		(property "Value" "R_4x0R_0201_array"
			(at 111.76 199.39 0)
			(effects
				(font
					(size 1.27 1.27)
					(thickness 0.15)
				)
				(justify left bottom)
				(hide yes)
			)
		)
		(property "Footprint" "antmicro-footprints:R_Array_4x0201_Panasonic_EXB18V"
			(at 111.76 204.47 0)
			(effects
				(font
					(size 1.27 1.27)
					(thickness 0.15)
				)
				(justify left bottom)
				(hide yes)
			)
		)
		(property "Datasheet" "http://industrial.panasonic.com/cdbs/www-data/pdf/AOC0000/AOC0000C14.pdf"
			(at 111.76 207.01 0)
			(effects
				(font
					(size 1.27 1.27)
					(thickness 0.15)
				)
				(justify left bottom)
				(hide yes)
			)
		)
		(property "Description" "Zero Ohm Network Resistor, Jumper, 0201 [0603 Metric], Thick Film, Isolated, Flat, 4 Resistors"
			(at 85.09 191.77 0)
			(effects
				(font
					(size 1.27 1.27)
				)
				(hide yes)
			)
		)
		(property "MPN" "EXB-18VR000X"
			(at 111.76 209.55 0)
			(effects
				(font
					(size 1.27 1.27)
					(thickness 0.15)
				)
				(justify left bottom)
				(hide yes)
			)
		)
		(property "Manufacturer" "Panasonic"
			(at 111.76 212.09 0)
			(effects
				(font
					(size 1.27 1.27)
					(thickness 0.15)
				)
				(justify left bottom)
				(hide yes)
			)
		)
		(property "Val" "4x0R_0201"
			(at 90.17 204.47 0)
			(effects
				(font
					(size 1.27 1.27)
					(thickness 0.15)
				)
			)
		)
		(property "Author" "Antmicro"
			(at 111.76 214.63 0)
			(effects
				(font
					(size 1.27 1.27)
					(thickness 0.15)
				)
				(justify left bottom)
				(hide yes)
			)
		)
		(property "License" "Apache-2.0"
			(at 111.76 217.17 0)
			(effects
				(font
					(size 1.27 1.27)
					(thickness 0.15)
				)
				(justify left bottom)
				(hide yes)
			)
		)
		(pin "1"
		)
		(pin "2"
		)
		(pin "3"
		)
		(pin "4"
		)
		(pin "5"
		)
		(pin "6"
		)
		(pin "7"
		)
		(pin "8"
		)
		(instances
			(project "polarfire-som"
				(path ""
					(reference "R24")
					(unit 1)
				)
			)
		)
	)
	(symbol
		(lib_id "antmicropower:GND")
		(at 318.77 149.86 0)
		(mirror y)
		(unit 1)
		(exclude_from_sim no)
		(in_bom yes)
		(on_board yes)
		(dnp no)
		(fields_autoplaced yes)
		(property "Reference" "#PWR0315"
			(at 309.88 152.4 0)
			(effects
				(font
					(size 1.27 1.27)
					(thickness 0.15)
				)
				(justify left bottom)
				(hide yes)
			)
		)
		(property "Value" "GND"
			(at 318.77 154.94 0)
			(effects
				(font
					(size 1.27 1.27)
					(thickness 0.15)
				)
			)
		)
		(property "Footprint" ""
			(at 309.88 157.48 0)
			(effects
				(font
					(size 1.27 1.27)
					(thickness 0.15)
				)
				(justify left bottom)
				(hide yes)
			)
		)
		(property "Datasheet" ""
			(at 309.88 162.56 0)
			(effects
				(font
					(size 1.27 1.27)
					(thickness 0.15)
				)
				(justify left bottom)
				(hide yes)
			)
		)
		(property "Description" ""
			(at 318.77 149.86 0)
			(effects
				(font
					(size 1.27 1.27)
				)
				(hide yes)
			)
		)
		(property "Author" "Antmicro"
			(at 309.88 157.48 0)
			(effects
				(font
					(size 1.27 1.27)
					(thickness 0.15)
				)
				(justify left bottom)
				(hide yes)
			)
		)
		(property "License" "Apache-2.0"
			(at 309.88 160.02 0)
			(effects
				(font
					(size 1.27 1.27)
					(thickness 0.15)
				)
				(justify left bottom)
				(hide yes)
			)
		)
		(pin "1"
		)
		(instances
			(project "polarfire-som"
				(path ""
					(reference "#PWR0315")
					(unit 1)
				)
			)
		)
	)
	(symbol
		(lib_id "antmicroFPGAChips:MPFS250T-FCVG484E")
		(at 290.83 64.77 0)
		(unit 3)
		(exclude_from_sim no)
		(in_bom yes)
		(on_board yes)
		(dnp no)
		(fields_autoplaced yes)
		(property "Reference" "U1"
			(at 308.61 54.61 0)
			(effects
				(font
					(size 1.27 1.27)
					(thickness 0.15)
				)
			)
		)
		(property "Value" "MPFS250T-FCVG484"
			(at 396.24 69.85 0)
			(effects
				(font
					(size 1.27 1.27)
					(thickness 0.15)
				)
				(justify left bottom)
				(hide yes)
			)
		)
		(property "Footprint" "antmicro-footprints:BGA-484_19x19mm_Layout22x22_P0.8mm_FCVG484"
			(at 396.24 72.39 0)
			(effects
				(font
					(size 1.27 1.27)
					(thickness 0.15)
				)
				(justify left bottom)
				(hide yes)
			)
		)
		(property "Datasheet" "https://ww1.microchip.com/downloads/aemDocuments/documents/FPGA/ProductDocuments/DataSheets/PolarFire-SoC-Datasheet-DS00004248.pdf"
			(at 396.24 74.93 0)
			(effects
				(font
					(size 1.27 1.27)
					(thickness 0.15)
				)
				(justify left bottom)
				(hide yes)
			)
		)
		(property "Description" "RISC-V System On Chip (SOC) IC PolarFire® FPGA - 254K Logic Modules 484-FCBGA (19x19)"
			(at 396.24 85.09 0)
			(effects
				(font
					(size 1.27 1.27)
				)
				(justify left bottom)
				(hide yes)
			)
		)
		(property "MPN" "MPFS250T-FCVG484E"
			(at 308.61 57.15 0)
			(effects
				(font
					(size 1.27 1.27)
					(thickness 0.15)
				)
			)
		)
		(property "Manufacturer" "Microchip Technology"
			(at 396.24 77.47 0)
			(effects
				(font
					(size 1.27 1.27)
					(thickness 0.15)
				)
				(justify left bottom)
				(hide yes)
			)
		)
		(property "VSD_class" "MPFS250T"
			(at 394.97 82.55 0)
			(effects
				(font
					(size 1.27 1.27)
					(thickness 0.15)
				)
				(justify left bottom)
				(hide yes)
			)
		)
		(property "Author" "Antmicro"
			(at 396.24 80.01 0)
			(effects
				(font
					(size 1.27 1.27)
					(thickness 0.15)
				)
				(justify left bottom)
				(hide yes)
			)
		)
		(property "License" "Apache-2.0"
			(at 396.24 82.55 0)
			(effects
				(font
					(size 1.27 1.27)
					(thickness 0.15)
				)
				(justify left bottom)
				(hide yes)
			)
		)
		(pin "AA12"
		)
		(pin "AA13"
		)
		(pin "AA15"
		)
		(pin "AA16"
		)
		(pin "AA17"
		)
		(pin "AA18"
		)
		(pin "AA20"
		)
		(pin "AA21"
		)
		(pin "AA22"
		)
		(pin "AB12"
		)
		(pin "AB13"
		)
		(pin "AB14"
		)
		(pin "AB15"
		)
		(pin "AB17"
		)
		(pin "AB18"
		)
		(pin "AB19"
		)
		(pin "AB20"
		)
		(pin "AB21"
		)
		(pin "R12"
		)
		(pin "R14"
		)
		(pin "R15"
		)
		(pin "R16"
		)
		(pin "T12"
		)
		(pin "T13"
		)
		(pin "T15"
		)
		(pin "T16"
		)
		(pin "T17"
		)
		(pin "U12"
		)
		(pin "U13"
		)
		(pin "U14"
		)
		(pin "U15"
		)
		(pin "U17"
		)
		(pin "U18"
		)
		(pin "U19"
		)
		(pin "V12"
		)
		(pin "V14"
		)
		(pin "V15"
		)
		(pin "V16"
		)
		(pin "V17"
		)
		(pin "V19"
		)
		(pin "V20"
		)
		(pin "V21"
		)
		(pin "V22"
		)
		(pin "W12"
		)
		(pin "W13"
		)
		(pin "W14"
		)
		(pin "W16"
		)
		(pin "W17"
		)
		(pin "W18"
		)
		(pin "W19"
		)
		(pin "W21"
		)
		(pin "W22"
		)
		(pin "Y13"
		)
		(pin "Y14"
		)
		(pin "Y15"
		)
		(pin "Y16"
		)
		(pin "Y18"
		)
		(pin "Y19"
		)
		(pin "Y20"
		)
		(pin "Y21"
		)
		(pin "A10"
		)
		(pin "A11"
		)
		(pin "A12"
		)
		(pin "A13"
		)
		(pin "A15"
		)
		(pin "A16"
		)
		(pin "A17"
		)
		(pin "A18"
		)
		(pin "A20"
		)
		(pin "A21"
		)
		(pin "A5"
		)
		(pin "A6"
		)
		(pin "A7"
		)
		(pin "A8"
		)
		(pin "B10"
		)
		(pin "B12"
		)
		(pin "B13"
		)
		(pin "B14"
		)
		(pin "B15"
		)
		(pin "B17"
		)
		(pin "B18"
		)
		(pin "B19"
		)
		(pin "B20"
		)
		(pin "B21"
		)
		(pin "B22"
		)
		(pin "B4"
		)
		(pin "B5"
		)
		(pin "B7"
		)
		(pin "B8"
		)
		(pin "B9"
		)
		(pin "C10"
		)
		(pin "C11"
		)
		(pin "C12"
		)
		(pin "C14"
		)
		(pin "C15"
		)
		(pin "C16"
		)
		(pin "C17"
		)
		(pin "C19"
		)
		(pin "C20"
		)
		(pin "C22"
		)
		(pin "C4"
		)
		(pin "C5"
		)
		(pin "C6"
		)
		(pin "C7"
		)
		(pin "C9"
		)
		(pin "D11"
		)
		(pin "D12"
		)
		(pin "D13"
		)
		(pin "D14"
		)
		(pin "D16"
		)
		(pin "D17"
		)
		(pin "D18"
		)
		(pin "D19"
		)
		(pin "D20"
		)
		(pin "D21"
		)
		(pin "D22"
		)
		(pin "D6"
		)
		(pin "D7"
		)
		(pin "D8"
		)
		(pin "D9"
		)
		(pin "E10"
		)
		(pin "E11"
		)
		(pin "E13"
		)
		(pin "E14"
		)
		(pin "E15"
		)
		(pin "E16"
		)
		(pin "E18"
		)
		(pin "E19"
		)
		(pin "F10"
		)
		(pin "F11"
		)
		(pin "F12"
		)
		(pin "F13"
		)
		(pin "F15"
		)
		(pin "F16"
		)
		(pin "F17"
		)
		(pin "G12"
		)
		(pin "G13"
		)
		(pin "G14"
		)
		(pin "G15"
		)
		(pin "G17"
		)
		(pin "H12"
		)
		(pin "H13"
		)
		(pin "H15"
		)
		(pin "H17"
		)
		(pin "A2"
		)
		(pin "A3"
		)
		(pin "B1"
		)
		(pin "B2"
		)
		(pin "B3"
		)
		(pin "C1"
		)
		(pin "C2"
		)
		(pin "D1"
		)
		(pin "D2"
		)
		(pin "D3"
		)
		(pin "D4"
		)
		(pin "E1"
		)
		(pin "E3"
		)
		(pin "E4"
		)
		(pin "E5"
		)
		(pin "F1"
		)
		(pin "F2"
		)
		(pin "F3"
		)
		(pin "F5"
		)
		(pin "F6"
		)
		(pin "G2"
		)
		(pin "G3"
		)
		(pin "G4"
		)
		(pin "G5"
		)
		(pin "E6"
		)
		(pin "E8"
		)
		(pin "E9"
		)
		(pin "F7"
		)
		(pin "F8"
		)
		(pin "G10"
		)
		(pin "G7"
		)
		(pin "G8"
		)
		(pin "G9"
		)
		(pin "H10"
		)
		(pin "H11"
		)
		(pin "H7"
		)
		(pin "H9"
		)
		(pin "H1"
		)
		(pin "H2"
		)
		(pin "H4"
		)
		(pin "H5"
		)
		(pin "H6"
		)
		(pin "J1"
		)
		(pin "J2"
		)
		(pin "J3"
		)
		(pin "J4"
		)
		(pin "J6"
		)
		(pin "J7"
		)
		(pin "K3"
		)
		(pin "K4"
		)
		(pin "K5"
		)
		(pin "K6"
		)
		(pin "K7"
		)
		(pin "L5"
		)
		(pin "L6"
		)
		(pin "L7"
		)
		(pin "L8"
		)
		(pin "M7"
		)
		(pin "N6"
		)
		(pin "N7"
		)
		(pin "N8"
		)
		(pin "AA1"
		)
		(pin "AA10"
		)
		(pin "AA11"
		)
		(pin "AA2"
		)
		(pin "AA3"
		)
		(pin "AA5"
		)
		(pin "AA6"
		)
		(pin "AA7"
		)
		(pin "AA8"
		)
		(pin "AB10"
		)
		(pin "AB2"
		)
		(pin "AB3"
		)
		(pin "AB4"
		)
		(pin "AB5"
		)
		(pin "AB7"
		)
		(pin "AB8"
		)
		(pin "AB9"
		)
		(pin "K1"
		)
		(pin "L1"
		)
		(pin "L2"
		)
		(pin "L3"
		)
		(pin "M2"
		)
		(pin "M3"
		)
		(pin "M4"
		)
		(pin "M5"
		)
		(pin "N1"
		)
		(pin "N2"
		)
		(pin "N4"
		)
		(pin "N5"
		)
		(pin "P1"
		)
		(pin "P2"
		)
		(pin "P3"
		)
		(pin "P4"
		)
		(pin "P6"
		)
		(pin "P7"
		)
		(pin "P8"
		)
		(pin "R1"
		)
		(pin "R10"
		)
		(pin "R11"
		)
		(pin "R3"
		)
		(pin "R4"
		)
		(pin "R5"
		)
		(pin "R6"
		)
		(pin "R8"
		)
		(pin "T1"
		)
		(pin "T10"
		)
		(pin "T11"
		)
		(pin "T2"
		)
		(pin "T3"
		)
		(pin "T5"
		)
		(pin "T6"
		)
		(pin "T7"
		)
		(pin "T8"
		)
		(pin "U10"
		)
		(pin "U2"
		)
		(pin "U3"
		)
		(pin "U4"
		)
		(pin "U5"
		)
		(pin "U7"
		)
		(pin "U8"
		)
		(pin "U9"
		)
		(pin "V1"
		)
		(pin "V10"
		)
		(pin "V11"
		)
		(pin "V2"
		)
		(pin "V4"
		)
		(pin "V5"
		)
		(pin "V6"
		)
		(pin "V7"
		)
		(pin "V9"
		)
		(pin "W1"
		)
		(pin "W11"
		)
		(pin "W2"
		)
		(pin "W3"
		)
		(pin "W4"
		)
		(pin "W6"
		)
		(pin "W7"
		)
		(pin "W8"
		)
		(pin "W9"
		)
		(pin "Y1"
		)
		(pin "Y10"
		)
		(pin "Y11"
		)
		(pin "Y3"
		)
		(pin "Y4"
		)
		(pin "Y5"
		)
		(pin "Y6"
		)
		(pin "Y8"
		)
		(pin "Y9"
		)
		(pin "F21"
		)
		(pin "F22"
		)
		(pin "G19"
		)
		(pin "G20"
		)
		(pin "H21"
		)
		(pin "H22"
		)
		(pin "J19"
		)
		(pin "J20"
		)
		(pin "K21"
		)
		(pin "K22"
		)
		(pin "L19"
		)
		(pin "L20"
		)
		(pin "M21"
		)
		(pin "M22"
		)
		(pin "N19"
		)
		(pin "N20"
		)
		(pin "P21"
		)
		(pin "P22"
		)
		(pin "R19"
		)
		(pin "R20"
		)
		(pin "T21"
		)
		(pin "T22"
		)
		(pin "A1"
		)
		(pin "A14"
		)
		(pin "A19"
		)
		(pin "A22"
		)
		(pin "A4"
		)
		(pin "A9"
		)
		(pin "AA14"
		)
		(pin "AA19"
		)
		(pin "AA4"
		)
		(pin "AA9"
		)
		(pin "AB1"
		)
		(pin "AB11"
		)
		(pin "AB16"
		)
		(pin "AB22"
		)
		(pin "AB6"
		)
		(pin "B11"
		)
		(pin "B16"
		)
		(pin "B6"
		)
		(pin "C13"
		)
		(pin "C18"
		)
		(pin "C21"
		)
		(pin "C3"
		)
		(pin "C8"
		)
		(pin "D10"
		)
		(pin "D15"
		)
		(pin "D5"
		)
		(pin "E12"
		)
		(pin "E17"
		)
		(pin "E2"
		)
		(pin "E20"
		)
		(pin "E21"
		)
		(pin "E22"
		)
		(pin "E7"
		)
		(pin "F14"
		)
		(pin "F18"
		)
		(pin "F19"
		)
		(pin "F20"
		)
		(pin "F4"
		)
		(pin "F9"
		)
		(pin "G1"
		)
		(pin "G11"
		)
		(pin "G16"
		)
		(pin "G18"
		)
		(pin "G21"
		)
		(pin "G22"
		)
		(pin "G6"
		)
		(pin "H14"
		)
		(pin "H16"
		)
		(pin "H18"
		)
		(pin "H19"
		)
		(pin "H20"
		)
		(pin "H3"
		)
		(pin "H8"
		)
		(pin "J10"
		)
		(pin "J11"
		)
		(pin "J12"
		)
		(pin "J13"
		)
		(pin "J14"
		)
		(pin "J15"
		)
		(pin "J16"
		)
		(pin "J17"
		)
		(pin "J18"
		)
		(pin "J21"
		)
		(pin "J22"
		)
		(pin "J5"
		)
		(pin "J8"
		)
		(pin "J9"
		)
		(pin "K10"
		)
		(pin "K11"
		)
		(pin "K12"
		)
		(pin "K13"
		)
		(pin "K14"
		)
		(pin "K15"
		)
		(pin "K16"
		)
		(pin "K17"
		)
		(pin "K18"
		)
		(pin "K19"
		)
		(pin "K2"
		)
		(pin "K20"
		)
		(pin "K8"
		)
		(pin "K9"
		)
		(pin "L10"
		)
		(pin "L11"
		)
		(pin "L12"
		)
		(pin "L13"
		)
		(pin "L14"
		)
		(pin "L15"
		)
		(pin "L16"
		)
		(pin "L17"
		)
		(pin "L18"
		)
		(pin "L21"
		)
		(pin "L22"
		)
		(pin "L4"
		)
		(pin "L9"
		)
		(pin "M1"
		)
		(pin "M10"
		)
		(pin "M11"
		)
		(pin "M12"
		)
		(pin "M13"
		)
		(pin "M14"
		)
		(pin "M15"
		)
		(pin "M16"
		)
		(pin "M17"
		)
		(pin "M18"
		)
		(pin "M19"
		)
		(pin "M20"
		)
		(pin "M6"
		)
		(pin "M8"
		)
		(pin "M9"
		)
		(pin "N10"
		)
		(pin "N11"
		)
		(pin "N12"
		)
		(pin "N13"
		)
		(pin "N14"
		)
		(pin "N15"
		)
		(pin "N16"
		)
		(pin "N17"
		)
		(pin "N18"
		)
		(pin "N21"
		)
		(pin "N22"
		)
		(pin "N3"
		)
		(pin "N9"
		)
		(pin "P10"
		)
		(pin "P11"
		)
		(pin "P12"
		)
		(pin "P13"
		)
		(pin "P14"
		)
		(pin "P15"
		)
		(pin "P16"
		)
		(pin "P17"
		)
		(pin "P18"
		)
		(pin "P19"
		)
		(pin "P20"
		)
		(pin "P5"
		)
		(pin "P9"
		)
		(pin "R13"
		)
		(pin "R17"
		)
		(pin "R18"
		)
		(pin "R2"
		)
		(pin "R21"
		)
		(pin "R22"
		)
		(pin "R7"
		)
		(pin "R9"
		)
		(pin "T14"
		)
		(pin "T18"
		)
		(pin "T19"
		)
		(pin "T20"
		)
		(pin "T4"
		)
		(pin "T9"
		)
		(pin "U1"
		)
		(pin "U11"
		)
		(pin "U16"
		)
		(pin "U20"
		)
		(pin "U21"
		)
		(pin "U22"
		)
		(pin "U6"
		)
		(pin "V13"
		)
		(pin "V18"
		)
		(pin "V3"
		)
		(pin "V8"
		)
		(pin "W10"
		)
		(pin "W15"
		)
		(pin "W20"
		)
		(pin "W5"
		)
		(pin "Y12"
		)
		(pin "Y17"
		)
		(pin "Y2"
		)
		(pin "Y22"
		)
		(pin "Y7"
		)
		(instances
			(project "polarfire-som"
				(path ""
					(reference "U1")
					(unit 3)
				)
			)
		)
	)
	(symbol
		(lib_id "antmicropower:VDDI")
		(at 293.37 132.08 0)
		(mirror y)
		(unit 1)
		(exclude_from_sim no)
		(in_bom yes)
		(on_board yes)
		(dnp no)
		(fields_autoplaced yes)
		(property "Reference" "#PWR0309"
			(at 293.37 135.89 0)
			(effects
				(font
					(size 1.27 1.27)
				)
				(hide yes)
			)
		)
		(property "Value" "VDD"
			(at 293.37 127.635 0)
			(effects
				(font
					(size 1.27 1.27)
				)
			)
		)
		(property "Footprint" ""
			(at 293.37 132.08 0)
			(effects
				(font
					(size 1.27 1.27)
				)
				(hide yes)
			)
		)
		(property "Datasheet" ""
			(at 293.37 132.08 0)
			(effects
				(font
					(size 1.27 1.27)
				)
				(hide yes)
			)
		)
		(property "Description" ""
			(at 293.37 132.08 0)
			(effects
				(font
					(size 1.27 1.27)
				)
				(hide yes)
			)
		)
		(pin "1"
		)
		(instances
			(project "polarfire-som"
				(path ""
					(reference "#PWR0309")
					(unit 1)
				)
			)
		)
	)
	(symbol
		(lib_id "antmicroResistorNetworksArrays:R_4x0R_0201_array")
		(at 123.19 172.72 0)
		(mirror y)
		(unit 1)
		(exclude_from_sim no)
		(in_bom yes)
		(on_board yes)
		(dnp yes)
		(property "Reference" "R26"
			(at 118.11 182.88 0)
			(effects
				(font
					(size 1.27 1.27)
					(thickness 0.15)
				)
			)
		)
		(property "Value" "R_4x0R_0201_array"
			(at 96.52 180.34 0)
			(effects
				(font
					(size 1.27 1.27)
					(thickness 0.15)
				)
				(justify left bottom)
				(hide yes)
			)
		)
		(property "Footprint" "antmicro-footprints:R_Array_4x0201_Panasonic_EXB18V"
			(at 96.52 185.42 0)
			(effects
				(font
					(size 1.27 1.27)
					(thickness 0.15)
				)
				(justify left bottom)
				(hide yes)
			)
		)
		(property "Datasheet" "http://industrial.panasonic.com/cdbs/www-data/pdf/AOC0000/AOC0000C14.pdf"
			(at 96.52 187.96 0)
			(effects
				(font
					(size 1.27 1.27)
					(thickness 0.15)
				)
				(justify left bottom)
				(hide yes)
			)
		)
		(property "Description" "Zero Ohm Network Resistor, Jumper, 0201 [0603 Metric], Thick Film, Isolated, Flat, 4 Resistors"
			(at 123.19 172.72 0)
			(effects
				(font
					(size 1.27 1.27)
				)
				(hide yes)
			)
		)
		(property "MPN" "EXB-18VR000X"
			(at 96.52 190.5 0)
			(effects
				(font
					(size 1.27 1.27)
					(thickness 0.15)
				)
				(justify left bottom)
				(hide yes)
			)
		)
		(property "Manufacturer" "Panasonic"
			(at 96.52 193.04 0)
			(effects
				(font
					(size 1.27 1.27)
					(thickness 0.15)
				)
				(justify left bottom)
				(hide yes)
			)
		)
		(property "Val" "4x0R_0201"
			(at 118.11 185.42 0)
			(effects
				(font
					(size 1.27 1.27)
					(thickness 0.15)
				)
			)
		)
		(property "Author" "Antmicro"
			(at 96.52 195.58 0)
			(effects
				(font
					(size 1.27 1.27)
					(thickness 0.15)
				)
				(justify left bottom)
				(hide yes)
			)
		)
		(property "License" "Apache-2.0"
			(at 96.52 198.12 0)
			(effects
				(font
					(size 1.27 1.27)
					(thickness 0.15)
				)
				(justify left bottom)
				(hide yes)
			)
		)
		(property "DNP" "DNP"
			(at 118.11 176.53 90)
			(effects
				(font
					(size 2.54 2.54)
					(bold yes)
				)
				(hide yes)
			)
		)
		(pin "1"
		)
		(pin "2"
		)
		(pin "3"
		)
		(pin "4"
		)
		(pin "5"
		)
		(pin "6"
		)
		(pin "7"
		)
		(pin "8"
		)
		(instances
			(project "polarfire-som"
				(path ""
					(reference "R26")
					(unit 1)
				)
			)
		)
	)
	(symbol
		(lib_id "antmicropower:VDDI")
		(at 289.56 181.61 0)
		(unit 1)
		(exclude_from_sim no)
		(in_bom yes)
		(on_board yes)
		(dnp no)
		(fields_autoplaced yes)
		(property "Reference" "#PWR0355"
			(at 289.56 185.42 0)
			(effects
				(font
					(size 1.27 1.27)
				)
				(hide yes)
			)
		)
		(property "Value" "VDD"
			(at 289.56 177.165 0)
			(effects
				(font
					(size 1.27 1.27)
				)
			)
		)
		(property "Footprint" ""
			(at 289.56 181.61 0)
			(effects
				(font
					(size 1.27 1.27)
				)
				(hide yes)
			)
		)
		(property "Datasheet" ""
			(at 289.56 181.61 0)
			(effects
				(font
					(size 1.27 1.27)
				)
				(hide yes)
			)
		)
		(property "Description" ""
			(at 289.56 181.61 0)
			(effects
				(font
					(size 1.27 1.27)
				)
				(hide yes)
			)
		)
		(pin "1"
		)
		(instances
			(project "polarfire-som"
				(path ""
					(reference "#PWR0355")
					(unit 1)
				)
			)
		)
	)
	(symbol
		(lib_id "antmicroLogicTranslatorsLevelShifters:NTS0102_XSON")
		(at 297.18 138.43 0)
		(unit 1)
		(exclude_from_sim no)
		(in_bom yes)
		(on_board yes)
		(dnp no)
		(fields_autoplaced yes)
		(property "Reference" "U30"
			(at 307.34 130.81 0)
			(effects
				(font
					(size 1.27 1.27)
					(thickness 0.15)
				)
			)
		)
		(property "Value" "NTS0102_XSON"
			(at 332.74 146.05 0)
			(effects
				(font
					(size 1.27 1.27)
					(thickness 0.15)
				)
				(justify left bottom)
				(hide yes)
			)
		)
		(property "Footprint" "antmicro-footprints:XSON-8_1x1.95mm_P0.5mm"
			(at 332.74 148.59 0)
			(effects
				(font
					(size 1.27 1.27)
					(thickness 0.15)
				)
				(justify left bottom)
				(hide yes)
			)
		)
		(property "Datasheet" "http://www.farnell.com/datasheets/1760723.pdf"
			(at 332.74 151.13 0)
			(effects
				(font
					(size 1.27 1.27)
					(thickness 0.15)
				)
				(justify left bottom)
				(hide yes)
			)
		)
		(property "Description" "Transceiver, 1.65 V to 3.6 V, XSON-8"
			(at 297.18 138.43 0)
			(effects
				(font
					(size 1.27 1.27)
				)
				(hide yes)
			)
		)
		(property "MPN" "NTS0102GT"
			(at 307.34 133.35 0)
			(effects
				(font
					(size 1.27 1.27)
					(thickness 0.15)
				)
			)
		)
		(property "Manufacturer" "NXP"
			(at 332.74 153.67 0)
			(effects
				(font
					(size 1.27 1.27)
					(thickness 0.15)
				)
				(justify left bottom)
				(hide yes)
			)
		)
		(property "Author" "Antmicro"
			(at 332.74 156.21 0)
			(effects
				(font
					(size 1.27 1.27)
					(thickness 0.15)
				)
				(justify left bottom)
				(hide yes)
			)
		)
		(property "License" "Apache-2.0"
			(at 332.74 158.75 0)
			(effects
				(font
					(size 1.27 1.27)
					(thickness 0.15)
				)
				(justify left bottom)
				(hide yes)
			)
		)
		(pin "2"
		)
		(pin "6"
		)
		(pin "7"
		)
		(pin "5"
		)
		(pin "4"
		)
		(pin "3"
		)
		(pin "1"
		)
		(pin "8"
		)
		(instances
			(project "polarfire-som"
				(path ""
					(reference "U30")
					(unit 1)
				)
			)
		)
	)
	(symbol
		(lib_id "antmicroResistorNetworksArrays:R_4x0R_0201_array")
		(at 85.09 161.29 0)
		(unit 1)
		(exclude_from_sim no)
		(in_bom yes)
		(on_board yes)
		(dnp no)
		(fields_autoplaced yes)
		(property "Reference" "R22"
			(at 90.17 154.94 0)
			(effects
				(font
					(size 1.27 1.27)
					(thickness 0.15)
				)
			)
		)
		(property "Value" "R_4x0R_0201_array"
			(at 111.76 168.91 0)
			(effects
				(font
					(size 1.27 1.27)
					(thickness 0.15)
				)
				(justify left bottom)
				(hide yes)
			)
		)
		(property "Footprint" "antmicro-footprints:R_Array_4x0201_Panasonic_EXB18V"
			(at 111.76 173.99 0)
			(effects
				(font
					(size 1.27 1.27)
					(thickness 0.15)
				)
				(justify left bottom)
				(hide yes)
			)
		)
		(property "Datasheet" "http://industrial.panasonic.com/cdbs/www-data/pdf/AOC0000/AOC0000C14.pdf"
			(at 111.76 176.53 0)
			(effects
				(font
					(size 1.27 1.27)
					(thickness 0.15)
				)
				(justify left bottom)
				(hide yes)
			)
		)
		(property "Description" "Zero Ohm Network Resistor, Jumper, 0201 [0603 Metric], Thick Film, Isolated, Flat, 4 Resistors"
			(at 85.09 161.29 0)
			(effects
				(font
					(size 1.27 1.27)
				)
				(hide yes)
			)
		)
		(property "MPN" "EXB-18VR000X"
			(at 111.76 179.07 0)
			(effects
				(font
					(size 1.27 1.27)
					(thickness 0.15)
				)
				(justify left bottom)
				(hide yes)
			)
		)
		(property "Manufacturer" "Panasonic"
			(at 111.76 181.61 0)
			(effects
				(font
					(size 1.27 1.27)
					(thickness 0.15)
				)
				(justify left bottom)
				(hide yes)
			)
		)
		(property "Val" "4x0R_0201"
			(at 90.17 157.48 0)
			(effects
				(font
					(size 1.27 1.27)
					(thickness 0.15)
				)
			)
		)
		(property "Author" "Antmicro"
			(at 111.76 184.15 0)
			(effects
				(font
					(size 1.27 1.27)
					(thickness 0.15)
				)
				(justify left bottom)
				(hide yes)
			)
		)
		(property "License" "Apache-2.0"
			(at 111.76 186.69 0)
			(effects
				(font
					(size 1.27 1.27)
					(thickness 0.15)
				)
				(justify left bottom)
				(hide yes)
			)
		)
		(pin "1"
		)
		(pin "2"
		)
		(pin "3"
		)
		(pin "4"
		)
		(pin "5"
		)
		(pin "6"
		)
		(pin "7"
		)
		(pin "8"
		)
		(instances
			(project "polarfire-som"
				(path ""
					(reference "R22")
					(unit 1)
				)
			)
		)
	)
	(symbol
		(lib_id "antmicroResistors0402:R_0R_0402")
		(at 309.88 214.63 0)
		(unit 1)
		(exclude_from_sim no)
		(in_bom yes)
		(on_board yes)
		(dnp no)
		(property "Reference" "R17"
			(at 309.88 212.09 0)
			(effects
				(font
					(size 1.27 1.27)
					(thickness 0.15)
				)
			)
		)
		(property "Value" "R_0R_0402"
			(at 330.2 227.33 0)
			(effects
				(font
					(size 1.27 1.27)
					(thickness 0.15)
				)
				(justify left bottom)
				(hide yes)
			)
		)
		(property "Footprint" "antmicro-footprints:R_0402_1005Metric"
			(at 330.2 229.87 0)
			(effects
				(font
					(size 1.27 1.27)
					(thickness 0.15)
				)
				(justify left bottom)
				(hide yes)
			)
		)
		(property "Datasheet" "https://industrial.panasonic.com/cdbs/www-data/pdf/RDA0000/AOA0000C301.pdf"
			(at 330.2 232.41 0)
			(effects
				(font
					(size 1.27 1.27)
					(thickness 0.15)
				)
				(justify left bottom)
				(hide yes)
			)
		)
		(property "Description" "SMD Chip Resistor, Jumper, 0 ohm, 100 mW, 0402 [1005 Metric], Thick Film, General Purpose"
			(at 309.88 214.63 0)
			(effects
				(font
					(size 1.27 1.27)
				)
				(hide yes)
			)
		)
		(property "MPN" "ERJ2GE0R00X"
			(at 330.2 234.95 0)
			(effects
				(font
					(size 1.27 1.27)
					(thickness 0.15)
				)
				(justify left bottom)
				(hide yes)
			)
		)
		(property "Manufacturer" "Panasonic"
			(at 330.2 237.49 0)
			(effects
				(font
					(size 1.27 1.27)
					(thickness 0.15)
				)
				(justify left bottom)
				(hide yes)
			)
		)
		(property "License" "Apache-2.0"
			(at 330.2 240.03 0)
			(effects
				(font
					(size 1.27 1.27)
					(thickness 0.15)
				)
				(justify left bottom)
				(hide yes)
			)
		)
		(property "Author" "Antmicro"
			(at 330.2 242.57 0)
			(effects
				(font
					(size 1.27 1.27)
					(thickness 0.15)
				)
				(justify left bottom)
				(hide yes)
			)
		)
		(property "Val" "0R"
			(at 314.96 212.09 0)
			(effects
				(font
					(size 1.27 1.27)
					(thickness 0.15)
				)
			)
		)
		(property "Tolerance" "~"
			(at 330.2 224.79 0)
			(effects
				(font
					(size 1.27 1.27)
				)
				(justify left bottom)
				(hide yes)
			)
		)
		(property "Current" "1A"
			(at 330.2 245.11 0)
			(effects
				(font
					(size 1.27 1.27)
					(thickness 0.15)
				)
				(justify left bottom)
				(hide yes)
			)
		)
		(property "Public" ""
			(at 330.2 245.11 0)
			(effects
				(font
					(size 1.27 1.27)
				)
				(justify left bottom)
				(hide yes)
			)
		)
		(pin "1"
		)
		(pin "2"
		)
		(instances
			(project "polarfire-som"
				(path ""
					(reference "R17")
					(unit 1)
				)
			)
		)
	)
	(symbol
		(lib_id "antmicroResistors0402:R_0R_0402")
		(at 335.28 90.17 0)
		(mirror x)
		(unit 1)
		(exclude_from_sim no)
		(in_bom yes)
		(on_board yes)
		(dnp no)
		(property "Reference" "R130"
			(at 332.74 91.44 0)
			(effects
				(font
					(size 1.27 1.27)
					(thickness 0.15)
				)
			)
		)
		(property "Value" "R_0R_0402"
			(at 355.6 77.47 0)
			(effects
				(font
					(size 1.27 1.27)
					(thickness 0.15)
				)
				(justify left bottom)
				(hide yes)
			)
		)
		(property "Footprint" "antmicro-footprints:R_0402_1005Metric"
			(at 355.6 74.93 0)
			(effects
				(font
					(size 1.27 1.27)
					(thickness 0.15)
				)
				(justify left bottom)
				(hide yes)
			)
		)
		(property "Datasheet" "https://industrial.panasonic.com/cdbs/www-data/pdf/RDA0000/AOA0000C301.pdf"
			(at 355.6 72.39 0)
			(effects
				(font
					(size 1.27 1.27)
					(thickness 0.15)
				)
				(justify left bottom)
				(hide yes)
			)
		)
		(property "Description" "SMD Chip Resistor, Jumper, 0 ohm, 100 mW, 0402 [1005 Metric], Thick Film, General Purpose"
			(at 335.28 90.17 0)
			(effects
				(font
					(size 1.27 1.27)
				)
				(hide yes)
			)
		)
		(property "MPN" "ERJ2GE0R00X"
			(at 355.6 69.85 0)
			(effects
				(font
					(size 1.27 1.27)
					(thickness 0.15)
				)
				(justify left bottom)
				(hide yes)
			)
		)
		(property "Manufacturer" "Panasonic"
			(at 355.6 67.31 0)
			(effects
				(font
					(size 1.27 1.27)
					(thickness 0.15)
				)
				(justify left bottom)
				(hide yes)
			)
		)
		(property "License" "Apache-2.0"
			(at 355.6 64.77 0)
			(effects
				(font
					(size 1.27 1.27)
					(thickness 0.15)
				)
				(justify left bottom)
				(hide yes)
			)
		)
		(property "Author" "Antmicro"
			(at 355.6 62.23 0)
			(effects
				(font
					(size 1.27 1.27)
					(thickness 0.15)
				)
				(justify left bottom)
				(hide yes)
			)
		)
		(property "Val" "0R"
			(at 342.9 91.44 0)
			(effects
				(font
					(size 1.27 1.27)
					(thickness 0.15)
				)
			)
		)
		(property "Tolerance" "~"
			(at 355.6 80.01 0)
			(effects
				(font
					(size 1.27 1.27)
				)
				(justify left bottom)
				(hide yes)
			)
		)
		(property "Current" "1A"
			(at 355.6 59.69 0)
			(effects
				(font
					(size 1.27 1.27)
					(thickness 0.15)
				)
				(justify left bottom)
				(hide yes)
			)
		)
		(property "Public" ""
			(at 355.6 59.69 0)
			(effects
				(font
					(size 1.27 1.27)
				)
				(justify left bottom)
				(hide yes)
			)
		)
		(pin "1"
		)
		(pin "2"
		)
		(instances
			(project "polarfire-som"
				(path ""
					(reference "R130")
					(unit 1)
				)
			)
		)
	)
	(symbol
		(lib_id "antmicroResistorNetworksArrays:R_4x0R_0201_array")
		(at 123.19 189.23 0)
		(mirror y)
		(unit 1)
		(exclude_from_sim no)
		(in_bom yes)
		(on_board yes)
		(dnp yes)
		(property "Reference" "R27"
			(at 118.11 199.39 0)
			(effects
				(font
					(size 1.27 1.27)
					(thickness 0.15)
				)
			)
		)
		(property "Value" "R_4x0R_0201_array"
			(at 96.52 196.85 0)
			(effects
				(font
					(size 1.27 1.27)
					(thickness 0.15)
				)
				(justify left bottom)
				(hide yes)
			)
		)
		(property "Footprint" "antmicro-footprints:R_Array_4x0201_Panasonic_EXB18V"
			(at 96.52 201.93 0)
			(effects
				(font
					(size 1.27 1.27)
					(thickness 0.15)
				)
				(justify left bottom)
				(hide yes)
			)
		)
		(property "Datasheet" "http://industrial.panasonic.com/cdbs/www-data/pdf/AOC0000/AOC0000C14.pdf"
			(at 96.52 204.47 0)
			(effects
				(font
					(size 1.27 1.27)
					(thickness 0.15)
				)
				(justify left bottom)
				(hide yes)
			)
		)
		(property "Description" "Zero Ohm Network Resistor, Jumper, 0201 [0603 Metric], Thick Film, Isolated, Flat, 4 Resistors"
			(at 123.19 189.23 0)
			(effects
				(font
					(size 1.27 1.27)
				)
				(hide yes)
			)
		)
		(property "MPN" "EXB-18VR000X"
			(at 96.52 207.01 0)
			(effects
				(font
					(size 1.27 1.27)
					(thickness 0.15)
				)
				(justify left bottom)
				(hide yes)
			)
		)
		(property "Manufacturer" "Panasonic"
			(at 96.52 209.55 0)
			(effects
				(font
					(size 1.27 1.27)
					(thickness 0.15)
				)
				(justify left bottom)
				(hide yes)
			)
		)
		(property "Val" "4x0R_0201"
			(at 118.11 201.93 0)
			(effects
				(font
					(size 1.27 1.27)
					(thickness 0.15)
				)
			)
		)
		(property "Author" "Antmicro"
			(at 96.52 212.09 0)
			(effects
				(font
					(size 1.27 1.27)
					(thickness 0.15)
				)
				(justify left bottom)
				(hide yes)
			)
		)
		(property "License" "Apache-2.0"
			(at 96.52 214.63 0)
			(effects
				(font
					(size 1.27 1.27)
					(thickness 0.15)
				)
				(justify left bottom)
				(hide yes)
			)
		)
		(property "DNP" "DNP"
			(at 118.11 193.04 90)
			(effects
				(font
					(size 2.54 2.54)
					(bold yes)
				)
				(hide yes)
			)
		)
		(pin "1"
		)
		(pin "2"
		)
		(pin "3"
		)
		(pin "4"
		)
		(pin "5"
		)
		(pin "6"
		)
		(pin "7"
		)
		(pin "8"
		)
		(instances
			(project "polarfire-som"
				(path ""
					(reference "R27")
					(unit 1)
				)
			)
		)
	)
	(symbol
		(lib_id "antmicroResistors0402:R_4k7_0402")
		(at 284.48 193.04 90)
		(unit 1)
		(exclude_from_sim no)
		(in_bom yes)
		(on_board yes)
		(dnp no)
		(fields_autoplaced yes)
		(property "Reference" "R105"
			(at 287.02 189.23 90)
			(effects
				(font
					(size 1.27 1.27)
					(thickness 0.15)
				)
				(justify right)
			)
		)
		(property "Value" "R_4k7_0402"
			(at 297.18 172.72 0)
			(effects
				(font
					(size 1.27 1.27)
					(thickness 0.15)
				)
				(justify left bottom)
				(hide yes)
			)
		)
		(property "Footprint" "antmicro-footprints:R_0402_1005Metric"
			(at 299.72 172.72 0)
			(effects
				(font
					(size 1.27 1.27)
					(thickness 0.15)
				)
				(justify left bottom)
				(hide yes)
			)
		)
		(property "Datasheet" "https://www.bourns.com/docs/product-datasheets/cr.pdf"
			(at 302.26 172.72 0)
			(effects
				(font
					(size 1.27 1.27)
					(thickness 0.15)
				)
				(justify left bottom)
				(hide yes)
			)
		)
		(property "Description" "SMD Chip Resistor, 4.7 kohm, ± 1%, 62.5 mW, 0402 [1005 Metric], Thick Film, General Purpose"
			(at 284.48 193.04 0)
			(effects
				(font
					(size 1.27 1.27)
				)
				(hide yes)
			)
		)
		(property "MPN" "CR0402-FX-4701GLF"
			(at 304.8 172.72 0)
			(effects
				(font
					(size 1.27 1.27)
					(thickness 0.15)
				)
				(justify left bottom)
				(hide yes)
			)
		)
		(property "Manufacturer" "Bourns"
			(at 307.34 172.72 0)
			(effects
				(font
					(size 1.27 1.27)
					(thickness 0.15)
				)
				(justify left bottom)
				(hide yes)
			)
		)
		(property "License" "Apache-2.0"
			(at 309.88 172.72 0)
			(effects
				(font
					(size 1.27 1.27)
					(thickness 0.15)
				)
				(justify left bottom)
				(hide yes)
			)
		)
		(property "Author" "Antmicro"
			(at 312.42 172.72 0)
			(effects
				(font
					(size 1.27 1.27)
					(thickness 0.15)
				)
				(justify left bottom)
				(hide yes)
			)
		)
		(property "Val" "4k7"
			(at 287.02 191.77 90)
			(effects
				(font
					(size 1.27 1.27)
					(thickness 0.15)
				)
				(justify right)
			)
		)
		(property "Tolerance" "1%"
			(at 294.64 172.72 0)
			(effects
				(font
					(size 1.27 1.27)
				)
				(justify left bottom)
				(hide yes)
			)
		)
		(property "Public" ""
			(at 314.96 172.72 0)
			(effects
				(font
					(size 1.27 1.27)
				)
				(justify left bottom)
				(hide yes)
			)
		)
		(pin "1"
		)
		(pin "2"
		)
		(instances
			(project "polarfire-som"
				(path ""
					(reference "R105")
					(unit 1)
				)
			)
		)
	)
	(symbol
		(lib_id "antmicroResistors0402:R_0R_0402")
		(at 335.28 87.63 0)
		(unit 1)
		(exclude_from_sim no)
		(in_bom yes)
		(on_board yes)
		(dnp no)
		(property "Reference" "R99"
			(at 332.74 86.36 0)
			(effects
				(font
					(size 1.27 1.27)
					(thickness 0.15)
				)
			)
		)
		(property "Value" "R_0R_0402"
			(at 355.6 100.33 0)
			(effects
				(font
					(size 1.27 1.27)
					(thickness 0.15)
				)
				(justify left bottom)
				(hide yes)
			)
		)
		(property "Footprint" "antmicro-footprints:R_0402_1005Metric"
			(at 355.6 102.87 0)
			(effects
				(font
					(size 1.27 1.27)
					(thickness 0.15)
				)
				(justify left bottom)
				(hide yes)
			)
		)
		(property "Datasheet" "https://industrial.panasonic.com/cdbs/www-data/pdf/RDA0000/AOA0000C301.pdf"
			(at 355.6 105.41 0)
			(effects
				(font
					(size 1.27 1.27)
					(thickness 0.15)
				)
				(justify left bottom)
				(hide yes)
			)
		)
		(property "Description" "SMD Chip Resistor, Jumper, 0 ohm, 100 mW, 0402 [1005 Metric], Thick Film, General Purpose"
			(at 335.28 87.63 0)
			(effects
				(font
					(size 1.27 1.27)
				)
				(hide yes)
			)
		)
		(property "MPN" "ERJ2GE0R00X"
			(at 355.6 107.95 0)
			(effects
				(font
					(size 1.27 1.27)
					(thickness 0.15)
				)
				(justify left bottom)
				(hide yes)
			)
		)
		(property "Manufacturer" "Panasonic"
			(at 355.6 110.49 0)
			(effects
				(font
					(size 1.27 1.27)
					(thickness 0.15)
				)
				(justify left bottom)
				(hide yes)
			)
		)
		(property "License" "Apache-2.0"
			(at 355.6 113.03 0)
			(effects
				(font
					(size 1.27 1.27)
					(thickness 0.15)
				)
				(justify left bottom)
				(hide yes)
			)
		)
		(property "Author" "Antmicro"
			(at 355.6 115.57 0)
			(effects
				(font
					(size 1.27 1.27)
					(thickness 0.15)
				)
				(justify left bottom)
				(hide yes)
			)
		)
		(property "Val" "0R"
			(at 342.9 86.36 0)
			(effects
				(font
					(size 1.27 1.27)
					(thickness 0.15)
				)
			)
		)
		(property "Tolerance" "~"
			(at 355.6 97.79 0)
			(effects
				(font
					(size 1.27 1.27)
				)
				(justify left bottom)
				(hide yes)
			)
		)
		(property "Current" "1A"
			(at 355.6 118.11 0)
			(effects
				(font
					(size 1.27 1.27)
					(thickness 0.15)
				)
				(justify left bottom)
				(hide yes)
			)
		)
		(property "Public" ""
			(at 355.6 118.11 0)
			(effects
				(font
					(size 1.27 1.27)
				)
				(justify left bottom)
				(hide yes)
			)
		)
		(pin "1"
		)
		(pin "2"
		)
		(instances
			(project "polarfire-som"
				(path ""
					(reference "R99")
					(unit 1)
				)
			)
		)
	)
	(symbol
		(lib_id "antmicroResistorNetworksArrays:R_4x0R_0201_array")
		(at 123.19 161.29 0)
		(mirror y)
		(unit 1)
		(exclude_from_sim no)
		(in_bom yes)
		(on_board yes)
		(dnp yes)
		(property "Reference" "R25"
			(at 118.11 154.94 0)
			(effects
				(font
					(size 1.27 1.27)
					(thickness 0.15)
				)
			)
		)
		(property "Value" "R_4x0R_0201_array"
			(at 96.52 168.91 0)
			(effects
				(font
					(size 1.27 1.27)
					(thickness 0.15)
				)
				(justify left bottom)
				(hide yes)
			)
		)
		(property "Footprint" "antmicro-footprints:R_Array_4x0201_Panasonic_EXB18V"
			(at 96.52 173.99 0)
			(effects
				(font
					(size 1.27 1.27)
					(thickness 0.15)
				)
				(justify left bottom)
				(hide yes)
			)
		)
		(property "Datasheet" "http://industrial.panasonic.com/cdbs/www-data/pdf/AOC0000/AOC0000C14.pdf"
			(at 96.52 176.53 0)
			(effects
				(font
					(size 1.27 1.27)
					(thickness 0.15)
				)
				(justify left bottom)
				(hide yes)
			)
		)
		(property "Description" "Zero Ohm Network Resistor, Jumper, 0201 [0603 Metric], Thick Film, Isolated, Flat, 4 Resistors"
			(at 123.19 161.29 0)
			(effects
				(font
					(size 1.27 1.27)
				)
				(hide yes)
			)
		)
		(property "MPN" "EXB-18VR000X"
			(at 96.52 179.07 0)
			(effects
				(font
					(size 1.27 1.27)
					(thickness 0.15)
				)
				(justify left bottom)
				(hide yes)
			)
		)
		(property "Manufacturer" "Panasonic"
			(at 96.52 181.61 0)
			(effects
				(font
					(size 1.27 1.27)
					(thickness 0.15)
				)
				(justify left bottom)
				(hide yes)
			)
		)
		(property "Val" "4x0R_0201"
			(at 118.11 157.48 0)
			(effects
				(font
					(size 1.27 1.27)
					(thickness 0.15)
				)
			)
		)
		(property "Author" "Antmicro"
			(at 96.52 184.15 0)
			(effects
				(font
					(size 1.27 1.27)
					(thickness 0.15)
				)
				(justify left bottom)
				(hide yes)
			)
		)
		(property "License" "Apache-2.0"
			(at 96.52 186.69 0)
			(effects
				(font
					(size 1.27 1.27)
					(thickness 0.15)
				)
				(justify left bottom)
				(hide yes)
			)
		)
		(property "DNP" "DNP"
			(at 118.11 165.1 90)
			(effects
				(font
					(size 2.54 2.54)
					(bold yes)
				)
				(hide yes)
			)
		)
		(pin "1"
		)
		(pin "2"
		)
		(pin "3"
		)
		(pin "4"
		)
		(pin "5"
		)
		(pin "6"
		)
		(pin "7"
		)
		(pin "8"
		)
		(instances
			(project "polarfire-som"
				(path ""
					(reference "R25")
					(unit 1)
				)
			)
		)
	)
	(symbol
		(lib_id "antmicroResistors0402:R_0R_0402")
		(at 309.88 217.17 0)
		(mirror x)
		(unit 1)
		(exclude_from_sim no)
		(in_bom yes)
		(on_board yes)
		(dnp no)
		(property "Reference" "R57"
			(at 309.88 219.71 0)
			(effects
				(font
					(size 1.27 1.27)
					(thickness 0.15)
				)
			)
		)
		(property "Value" "R_0R_0402"
			(at 330.2 204.47 0)
			(effects
				(font
					(size 1.27 1.27)
					(thickness 0.15)
				)
				(justify left bottom)
				(hide yes)
			)
		)
		(property "Footprint" "antmicro-footprints:R_0402_1005Metric"
			(at 330.2 201.93 0)
			(effects
				(font
					(size 1.27 1.27)
					(thickness 0.15)
				)
				(justify left bottom)
				(hide yes)
			)
		)
		(property "Datasheet" "https://industrial.panasonic.com/cdbs/www-data/pdf/RDA0000/AOA0000C301.pdf"
			(at 330.2 199.39 0)
			(effects
				(font
					(size 1.27 1.27)
					(thickness 0.15)
				)
				(justify left bottom)
				(hide yes)
			)
		)
		(property "Description" "SMD Chip Resistor, Jumper, 0 ohm, 100 mW, 0402 [1005 Metric], Thick Film, General Purpose"
			(at 309.88 217.17 0)
			(effects
				(font
					(size 1.27 1.27)
				)
				(hide yes)
			)
		)
		(property "MPN" "ERJ2GE0R00X"
			(at 330.2 196.85 0)
			(effects
				(font
					(size 1.27 1.27)
					(thickness 0.15)
				)
				(justify left bottom)
				(hide yes)
			)
		)
		(property "Manufacturer" "Panasonic"
			(at 330.2 194.31 0)
			(effects
				(font
					(size 1.27 1.27)
					(thickness 0.15)
				)
				(justify left bottom)
				(hide yes)
			)
		)
		(property "License" "Apache-2.0"
			(at 330.2 191.77 0)
			(effects
				(font
					(size 1.27 1.27)
					(thickness 0.15)
				)
				(justify left bottom)
				(hide yes)
			)
		)
		(property "Author" "Antmicro"
			(at 330.2 189.23 0)
			(effects
				(font
					(size 1.27 1.27)
					(thickness 0.15)
				)
				(justify left bottom)
				(hide yes)
			)
		)
		(property "Val" "0R"
			(at 314.96 219.71 0)
			(effects
				(font
					(size 1.27 1.27)
					(thickness 0.15)
				)
			)
		)
		(property "Tolerance" "~"
			(at 330.2 207.01 0)
			(effects
				(font
					(size 1.27 1.27)
				)
				(justify left bottom)
				(hide yes)
			)
		)
		(property "Current" "1A"
			(at 330.2 186.69 0)
			(effects
				(font
					(size 1.27 1.27)
					(thickness 0.15)
				)
				(justify left bottom)
				(hide yes)
			)
		)
		(property "Public" ""
			(at 330.2 186.69 0)
			(effects
				(font
					(size 1.27 1.27)
				)
				(justify left bottom)
				(hide yes)
			)
		)
		(pin "1"
		)
		(pin "2"
		)
		(instances
			(project "polarfire-som"
				(path ""
					(reference "R57")
					(unit 1)
				)
			)
		)
	)
	(symbol
		(lib_id "antmicropower:+3V3")
		(at 318.77 132.08 0)
		(mirror y)
		(unit 1)
		(exclude_from_sim no)
		(in_bom yes)
		(on_board yes)
		(dnp no)
		(fields_autoplaced yes)
		(property "Reference" "#PWR0314"
			(at 303.53 132.08 0)
			(effects
				(font
					(size 1.27 1.27)
					(thickness 0.15)
				)
				(justify left bottom)
				(hide yes)
			)
		)
		(property "Value" "+3V3"
			(at 318.77 127 0)
			(effects
				(font
					(size 1.27 1.27)
					(thickness 0.15)
				)
			)
		)
		(property "Footprint" ""
			(at 303.53 139.7 0)
			(effects
				(font
					(size 1.27 1.27)
					(thickness 0.15)
				)
				(justify left bottom)
				(hide yes)
			)
		)
		(property "Datasheet" ""
			(at 303.53 142.24 0)
			(effects
				(font
					(size 1.27 1.27)
					(thickness 0.15)
				)
				(justify left bottom)
				(hide yes)
			)
		)
		(property "Description" ""
			(at 318.77 132.08 0)
			(effects
				(font
					(size 1.27 1.27)
				)
				(hide yes)
			)
		)
		(property "Author" "Antmicro"
			(at 303.53 134.62 0)
			(effects
				(font
					(size 1.27 1.27)
					(thickness 0.15)
				)
				(justify left bottom)
				(hide yes)
			)
		)
		(property "License" "Apache-2.0"
			(at 303.53 137.16 0)
			(effects
				(font
					(size 1.27 1.27)
					(thickness 0.15)
				)
				(justify left bottom)
				(hide yes)
			)
		)
		(pin "1"
		)
		(instances
			(project "polarfire-som"
				(path ""
					(reference "#PWR0314")
					(unit 1)
				)
			)
		)
	)
	(symbol
		(lib_id "antmicroResistors0402:R_4k7_0402")
		(at 293.37 193.04 90)
		(unit 1)
		(exclude_from_sim no)
		(in_bom yes)
		(on_board yes)
		(dnp no)
		(fields_autoplaced yes)
		(property "Reference" "R106"
			(at 295.91 189.23 90)
			(effects
				(font
					(size 1.27 1.27)
					(thickness 0.15)
				)
				(justify right)
			)
		)
		(property "Value" "R_4k7_0402"
			(at 306.07 172.72 0)
			(effects
				(font
					(size 1.27 1.27)
					(thickness 0.15)
				)
				(justify left bottom)
				(hide yes)
			)
		)
		(property "Footprint" "antmicro-footprints:R_0402_1005Metric"
			(at 308.61 172.72 0)
			(effects
				(font
					(size 1.27 1.27)
					(thickness 0.15)
				)
				(justify left bottom)
				(hide yes)
			)
		)
		(property "Datasheet" "https://www.bourns.com/docs/product-datasheets/cr.pdf"
			(at 311.15 172.72 0)
			(effects
				(font
					(size 1.27 1.27)
					(thickness 0.15)
				)
				(justify left bottom)
				(hide yes)
			)
		)
		(property "Description" "SMD Chip Resistor, 4.7 kohm, ± 1%, 62.5 mW, 0402 [1005 Metric], Thick Film, General Purpose"
			(at 293.37 193.04 0)
			(effects
				(font
					(size 1.27 1.27)
				)
				(hide yes)
			)
		)
		(property "MPN" "CR0402-FX-4701GLF"
			(at 313.69 172.72 0)
			(effects
				(font
					(size 1.27 1.27)
					(thickness 0.15)
				)
				(justify left bottom)
				(hide yes)
			)
		)
		(property "Manufacturer" "Bourns"
			(at 316.23 172.72 0)
			(effects
				(font
					(size 1.27 1.27)
					(thickness 0.15)
				)
				(justify left bottom)
				(hide yes)
			)
		)
		(property "License" "Apache-2.0"
			(at 318.77 172.72 0)
			(effects
				(font
					(size 1.27 1.27)
					(thickness 0.15)
				)
				(justify left bottom)
				(hide yes)
			)
		)
		(property "Author" "Antmicro"
			(at 321.31 172.72 0)
			(effects
				(font
					(size 1.27 1.27)
					(thickness 0.15)
				)
				(justify left bottom)
				(hide yes)
			)
		)
		(property "Val" "4k7"
			(at 295.91 191.77 90)
			(effects
				(font
					(size 1.27 1.27)
					(thickness 0.15)
				)
				(justify right)
			)
		)
		(property "Tolerance" "1%"
			(at 303.53 172.72 0)
			(effects
				(font
					(size 1.27 1.27)
				)
				(justify left bottom)
				(hide yes)
			)
		)
		(property "Public" ""
			(at 323.85 172.72 0)
			(effects
				(font
					(size 1.27 1.27)
				)
				(justify left bottom)
				(hide yes)
			)
		)
		(pin "1"
		)
		(pin "2"
		)
		(instances
			(project "polarfire-som"
				(path ""
					(reference "R106")
					(unit 1)
				)
			)
		)
	)
	(symbol
		(lib_id "antmicroResistorNetworksArrays:R_4x0R_0201_array")
		(at 85.09 172.72 0)
		(unit 1)
		(exclude_from_sim no)
		(in_bom yes)
		(on_board yes)
		(dnp no)
		(property "Reference" "R23"
			(at 90.17 182.88 0)
			(effects
				(font
					(size 1.27 1.27)
					(thickness 0.15)
				)
			)
		)
		(property "Value" "R_4x0R_0201_array"
			(at 111.76 180.34 0)
			(effects
				(font
					(size 1.27 1.27)
					(thickness 0.15)
				)
				(justify left bottom)
				(hide yes)
			)
		)
		(property "Footprint" "antmicro-footprints:R_Array_4x0201_Panasonic_EXB18V"
			(at 111.76 185.42 0)
			(effects
				(font
					(size 1.27 1.27)
					(thickness 0.15)
				)
				(justify left bottom)
				(hide yes)
			)
		)
		(property "Datasheet" "http://industrial.panasonic.com/cdbs/www-data/pdf/AOC0000/AOC0000C14.pdf"
			(at 111.76 187.96 0)
			(effects
				(font
					(size 1.27 1.27)
					(thickness 0.15)
				)
				(justify left bottom)
				(hide yes)
			)
		)
		(property "Description" "Zero Ohm Network Resistor, Jumper, 0201 [0603 Metric], Thick Film, Isolated, Flat, 4 Resistors"
			(at 85.09 172.72 0)
			(effects
				(font
					(size 1.27 1.27)
				)
				(hide yes)
			)
		)
		(property "MPN" "EXB-18VR000X"
			(at 111.76 190.5 0)
			(effects
				(font
					(size 1.27 1.27)
					(thickness 0.15)
				)
				(justify left bottom)
				(hide yes)
			)
		)
		(property "Manufacturer" "Panasonic"
			(at 111.76 193.04 0)
			(effects
				(font
					(size 1.27 1.27)
					(thickness 0.15)
				)
				(justify left bottom)
				(hide yes)
			)
		)
		(property "Val" "4x0R_0201"
			(at 90.17 185.42 0)
			(effects
				(font
					(size 1.27 1.27)
					(thickness 0.15)
				)
			)
		)
		(property "Author" "Antmicro"
			(at 111.76 195.58 0)
			(effects
				(font
					(size 1.27 1.27)
					(thickness 0.15)
				)
				(justify left bottom)
				(hide yes)
			)
		)
		(property "License" "Apache-2.0"
			(at 111.76 198.12 0)
			(effects
				(font
					(size 1.27 1.27)
					(thickness 0.15)
				)
				(justify left bottom)
				(hide yes)
			)
		)
		(pin "1"
		)
		(pin "2"
		)
		(pin "3"
		)
		(pin "4"
		)
		(pin "5"
		)
		(pin "6"
		)
		(pin "7"
		)
		(pin "8"
		)
		(instances
			(project "polarfire-som"
				(path ""
					(reference "R23")
					(unit 1)
				)
			)
		)
	)
	(symbol
		(lib_id "antmicroFPGAChips:MPFS250T-FCVG484E")
		(at 86.36 68.58 0)
		(unit 5)
		(exclude_from_sim no)
		(in_bom yes)
		(on_board yes)
		(dnp no)
		(fields_autoplaced yes)
		(property "Reference" "U1"
			(at 104.14 58.42 0)
			(effects
				(font
					(size 1.27 1.27)
					(thickness 0.15)
				)
			)
		)
		(property "Value" "MPFS250T-FCVG484"
			(at 191.77 73.66 0)
			(effects
				(font
					(size 1.27 1.27)
					(thickness 0.15)
				)
				(justify left bottom)
				(hide yes)
			)
		)
		(property "Footprint" "antmicro-footprints:BGA-484_19x19mm_Layout22x22_P0.8mm_FCVG484"
			(at 191.77 76.2 0)
			(effects
				(font
					(size 1.27 1.27)
					(thickness 0.15)
				)
				(justify left bottom)
				(hide yes)
			)
		)
		(property "Datasheet" "https://ww1.microchip.com/downloads/aemDocuments/documents/FPGA/ProductDocuments/DataSheets/PolarFire-SoC-Datasheet-DS00004248.pdf"
			(at 191.77 78.74 0)
			(effects
				(font
					(size 1.27 1.27)
					(thickness 0.15)
				)
				(justify left bottom)
				(hide yes)
			)
		)
		(property "Description" "RISC-V System On Chip (SOC) IC PolarFire® FPGA - 254K Logic Modules 484-FCBGA (19x19)"
			(at 191.77 88.9 0)
			(effects
				(font
					(size 1.27 1.27)
				)
				(justify left bottom)
				(hide yes)
			)
		)
		(property "MPN" "MPFS250T-FCVG484E"
			(at 104.14 60.96 0)
			(effects
				(font
					(size 1.27 1.27)
					(thickness 0.15)
				)
			)
		)
		(property "Manufacturer" "Microchip Technology"
			(at 191.77 81.28 0)
			(effects
				(font
					(size 1.27 1.27)
					(thickness 0.15)
				)
				(justify left bottom)
				(hide yes)
			)
		)
		(property "VSD_class" "MPFS250T"
			(at 190.5 86.36 0)
			(effects
				(font
					(size 1.27 1.27)
					(thickness 0.15)
				)
				(justify left bottom)
				(hide yes)
			)
		)
		(property "Author" "Antmicro"
			(at 191.77 83.82 0)
			(effects
				(font
					(size 1.27 1.27)
					(thickness 0.15)
				)
				(justify left bottom)
				(hide yes)
			)
		)
		(property "License" "Apache-2.0"
			(at 191.77 86.36 0)
			(effects
				(font
					(size 1.27 1.27)
					(thickness 0.15)
				)
				(justify left bottom)
				(hide yes)
			)
		)
		(pin "AA12"
		)
		(pin "AA13"
		)
		(pin "AA15"
		)
		(pin "AA16"
		)
		(pin "AA17"
		)
		(pin "AA18"
		)
		(pin "AA20"
		)
		(pin "AA21"
		)
		(pin "AA22"
		)
		(pin "AB12"
		)
		(pin "AB13"
		)
		(pin "AB14"
		)
		(pin "AB15"
		)
		(pin "AB17"
		)
		(pin "AB18"
		)
		(pin "AB19"
		)
		(pin "AB20"
		)
		(pin "AB21"
		)
		(pin "R12"
		)
		(pin "R14"
		)
		(pin "R15"
		)
		(pin "R16"
		)
		(pin "T12"
		)
		(pin "T13"
		)
		(pin "T15"
		)
		(pin "T16"
		)
		(pin "T17"
		)
		(pin "U12"
		)
		(pin "U13"
		)
		(pin "U14"
		)
		(pin "U15"
		)
		(pin "U17"
		)
		(pin "U18"
		)
		(pin "U19"
		)
		(pin "V12"
		)
		(pin "V14"
		)
		(pin "V15"
		)
		(pin "V16"
		)
		(pin "V17"
		)
		(pin "V19"
		)
		(pin "V20"
		)
		(pin "V21"
		)
		(pin "V22"
		)
		(pin "W12"
		)
		(pin "W13"
		)
		(pin "W14"
		)
		(pin "W16"
		)
		(pin "W17"
		)
		(pin "W18"
		)
		(pin "W19"
		)
		(pin "W21"
		)
		(pin "W22"
		)
		(pin "Y13"
		)
		(pin "Y14"
		)
		(pin "Y15"
		)
		(pin "Y16"
		)
		(pin "Y18"
		)
		(pin "Y19"
		)
		(pin "Y20"
		)
		(pin "Y21"
		)
		(pin "A10"
		)
		(pin "A11"
		)
		(pin "A12"
		)
		(pin "A13"
		)
		(pin "A15"
		)
		(pin "A16"
		)
		(pin "A17"
		)
		(pin "A18"
		)
		(pin "A20"
		)
		(pin "A21"
		)
		(pin "A5"
		)
		(pin "A6"
		)
		(pin "A7"
		)
		(pin "A8"
		)
		(pin "B10"
		)
		(pin "B12"
		)
		(pin "B13"
		)
		(pin "B14"
		)
		(pin "B15"
		)
		(pin "B17"
		)
		(pin "B18"
		)
		(pin "B19"
		)
		(pin "B20"
		)
		(pin "B21"
		)
		(pin "B22"
		)
		(pin "B4"
		)
		(pin "B5"
		)
		(pin "B7"
		)
		(pin "B8"
		)
		(pin "B9"
		)
		(pin "C10"
		)
		(pin "C11"
		)
		(pin "C12"
		)
		(pin "C14"
		)
		(pin "C15"
		)
		(pin "C16"
		)
		(pin "C17"
		)
		(pin "C19"
		)
		(pin "C20"
		)
		(pin "C22"
		)
		(pin "C4"
		)
		(pin "C5"
		)
		(pin "C6"
		)
		(pin "C7"
		)
		(pin "C9"
		)
		(pin "D11"
		)
		(pin "D12"
		)
		(pin "D13"
		)
		(pin "D14"
		)
		(pin "D16"
		)
		(pin "D17"
		)
		(pin "D18"
		)
		(pin "D19"
		)
		(pin "D20"
		)
		(pin "D21"
		)
		(pin "D22"
		)
		(pin "D6"
		)
		(pin "D7"
		)
		(pin "D8"
		)
		(pin "D9"
		)
		(pin "E10"
		)
		(pin "E11"
		)
		(pin "E13"
		)
		(pin "E14"
		)
		(pin "E15"
		)
		(pin "E16"
		)
		(pin "E18"
		)
		(pin "E19"
		)
		(pin "F10"
		)
		(pin "F11"
		)
		(pin "F12"
		)
		(pin "F13"
		)
		(pin "F15"
		)
		(pin "F16"
		)
		(pin "F17"
		)
		(pin "G12"
		)
		(pin "G13"
		)
		(pin "G14"
		)
		(pin "G15"
		)
		(pin "G17"
		)
		(pin "H12"
		)
		(pin "H13"
		)
		(pin "H15"
		)
		(pin "H17"
		)
		(pin "A2"
		)
		(pin "A3"
		)
		(pin "B1"
		)
		(pin "B2"
		)
		(pin "B3"
		)
		(pin "C1"
		)
		(pin "C2"
		)
		(pin "D1"
		)
		(pin "D2"
		)
		(pin "D3"
		)
		(pin "D4"
		)
		(pin "E1"
		)
		(pin "E3"
		)
		(pin "E4"
		)
		(pin "E5"
		)
		(pin "F1"
		)
		(pin "F2"
		)
		(pin "F3"
		)
		(pin "F5"
		)
		(pin "F6"
		)
		(pin "G2"
		)
		(pin "G3"
		)
		(pin "G4"
		)
		(pin "G5"
		)
		(pin "E6"
		)
		(pin "E8"
		)
		(pin "E9"
		)
		(pin "F7"
		)
		(pin "F8"
		)
		(pin "G10"
		)
		(pin "G7"
		)
		(pin "G8"
		)
		(pin "G9"
		)
		(pin "H10"
		)
		(pin "H11"
		)
		(pin "H7"
		)
		(pin "H9"
		)
		(pin "H1"
		)
		(pin "H2"
		)
		(pin "H4"
		)
		(pin "H5"
		)
		(pin "H6"
		)
		(pin "J1"
		)
		(pin "J2"
		)
		(pin "J3"
		)
		(pin "J4"
		)
		(pin "J6"
		)
		(pin "J7"
		)
		(pin "K3"
		)
		(pin "K4"
		)
		(pin "K5"
		)
		(pin "K6"
		)
		(pin "K7"
		)
		(pin "L5"
		)
		(pin "L6"
		)
		(pin "L7"
		)
		(pin "L8"
		)
		(pin "M7"
		)
		(pin "N6"
		)
		(pin "N7"
		)
		(pin "N8"
		)
		(pin "AA1"
		)
		(pin "AA10"
		)
		(pin "AA11"
		)
		(pin "AA2"
		)
		(pin "AA3"
		)
		(pin "AA5"
		)
		(pin "AA6"
		)
		(pin "AA7"
		)
		(pin "AA8"
		)
		(pin "AB10"
		)
		(pin "AB2"
		)
		(pin "AB3"
		)
		(pin "AB4"
		)
		(pin "AB5"
		)
		(pin "AB7"
		)
		(pin "AB8"
		)
		(pin "AB9"
		)
		(pin "K1"
		)
		(pin "L1"
		)
		(pin "L2"
		)
		(pin "L3"
		)
		(pin "M2"
		)
		(pin "M3"
		)
		(pin "M4"
		)
		(pin "M5"
		)
		(pin "N1"
		)
		(pin "N2"
		)
		(pin "N4"
		)
		(pin "N5"
		)
		(pin "P1"
		)
		(pin "P2"
		)
		(pin "P3"
		)
		(pin "P4"
		)
		(pin "P6"
		)
		(pin "P7"
		)
		(pin "P8"
		)
		(pin "R1"
		)
		(pin "R10"
		)
		(pin "R11"
		)
		(pin "R3"
		)
		(pin "R4"
		)
		(pin "R5"
		)
		(pin "R6"
		)
		(pin "R8"
		)
		(pin "T1"
		)
		(pin "T10"
		)
		(pin "T11"
		)
		(pin "T2"
		)
		(pin "T3"
		)
		(pin "T5"
		)
		(pin "T6"
		)
		(pin "T7"
		)
		(pin "T8"
		)
		(pin "U10"
		)
		(pin "U2"
		)
		(pin "U3"
		)
		(pin "U4"
		)
		(pin "U5"
		)
		(pin "U7"
		)
		(pin "U8"
		)
		(pin "U9"
		)
		(pin "V1"
		)
		(pin "V10"
		)
		(pin "V11"
		)
		(pin "V2"
		)
		(pin "V4"
		)
		(pin "V5"
		)
		(pin "V6"
		)
		(pin "V7"
		)
		(pin "V9"
		)
		(pin "W1"
		)
		(pin "W11"
		)
		(pin "W2"
		)
		(pin "W3"
		)
		(pin "W4"
		)
		(pin "W6"
		)
		(pin "W7"
		)
		(pin "W8"
		)
		(pin "W9"
		)
		(pin "Y1"
		)
		(pin "Y10"
		)
		(pin "Y11"
		)
		(pin "Y3"
		)
		(pin "Y4"
		)
		(pin "Y5"
		)
		(pin "Y6"
		)
		(pin "Y8"
		)
		(pin "Y9"
		)
		(pin "F21"
		)
		(pin "F22"
		)
		(pin "G19"
		)
		(pin "G20"
		)
		(pin "H21"
		)
		(pin "H22"
		)
		(pin "J19"
		)
		(pin "J20"
		)
		(pin "K21"
		)
		(pin "K22"
		)
		(pin "L19"
		)
		(pin "L20"
		)
		(pin "M21"
		)
		(pin "M22"
		)
		(pin "N19"
		)
		(pin "N20"
		)
		(pin "P21"
		)
		(pin "P22"
		)
		(pin "R19"
		)
		(pin "R20"
		)
		(pin "T21"
		)
		(pin "T22"
		)
		(pin "A1"
		)
		(pin "A14"
		)
		(pin "A19"
		)
		(pin "A22"
		)
		(pin "A4"
		)
		(pin "A9"
		)
		(pin "AA14"
		)
		(pin "AA19"
		)
		(pin "AA4"
		)
		(pin "AA9"
		)
		(pin "AB1"
		)
		(pin "AB11"
		)
		(pin "AB16"
		)
		(pin "AB22"
		)
		(pin "AB6"
		)
		(pin "B11"
		)
		(pin "B16"
		)
		(pin "B6"
		)
		(pin "C13"
		)
		(pin "C18"
		)
		(pin "C21"
		)
		(pin "C3"
		)
		(pin "C8"
		)
		(pin "D10"
		)
		(pin "D15"
		)
		(pin "D5"
		)
		(pin "E12"
		)
		(pin "E17"
		)
		(pin "E2"
		)
		(pin "E20"
		)
		(pin "E21"
		)
		(pin "E22"
		)
		(pin "E7"
		)
		(pin "F14"
		)
		(pin "F18"
		)
		(pin "F19"
		)
		(pin "F20"
		)
		(pin "F4"
		)
		(pin "F9"
		)
		(pin "G1"
		)
		(pin "G11"
		)
		(pin "G16"
		)
		(pin "G18"
		)
		(pin "G21"
		)
		(pin "G22"
		)
		(pin "G6"
		)
		(pin "H14"
		)
		(pin "H16"
		)
		(pin "H18"
		)
		(pin "H19"
		)
		(pin "H20"
		)
		(pin "H3"
		)
		(pin "H8"
		)
		(pin "J10"
		)
		(pin "J11"
		)
		(pin "J12"
		)
		(pin "J13"
		)
		(pin "J14"
		)
		(pin "J15"
		)
		(pin "J16"
		)
		(pin "J17"
		)
		(pin "J18"
		)
		(pin "J21"
		)
		(pin "J22"
		)
		(pin "J5"
		)
		(pin "J8"
		)
		(pin "J9"
		)
		(pin "K10"
		)
		(pin "K11"
		)
		(pin "K12"
		)
		(pin "K13"
		)
		(pin "K14"
		)
		(pin "K15"
		)
		(pin "K16"
		)
		(pin "K17"
		)
		(pin "K18"
		)
		(pin "K19"
		)
		(pin "K2"
		)
		(pin "K20"
		)
		(pin "K8"
		)
		(pin "K9"
		)
		(pin "L10"
		)
		(pin "L11"
		)
		(pin "L12"
		)
		(pin "L13"
		)
		(pin "L14"
		)
		(pin "L15"
		)
		(pin "L16"
		)
		(pin "L17"
		)
		(pin "L18"
		)
		(pin "L21"
		)
		(pin "L22"
		)
		(pin "L4"
		)
		(pin "L9"
		)
		(pin "M1"
		)
		(pin "M10"
		)
		(pin "M11"
		)
		(pin "M12"
		)
		(pin "M13"
		)
		(pin "M14"
		)
		(pin "M15"
		)
		(pin "M16"
		)
		(pin "M17"
		)
		(pin "M18"
		)
		(pin "M19"
		)
		(pin "M20"
		)
		(pin "M6"
		)
		(pin "M8"
		)
		(pin "M9"
		)
		(pin "N10"
		)
		(pin "N11"
		)
		(pin "N12"
		)
		(pin "N13"
		)
		(pin "N14"
		)
		(pin "N15"
		)
		(pin "N16"
		)
		(pin "N17"
		)
		(pin "N18"
		)
		(pin "N21"
		)
		(pin "N22"
		)
		(pin "N3"
		)
		(pin "N9"
		)
		(pin "P10"
		)
		(pin "P11"
		)
		(pin "P12"
		)
		(pin "P13"
		)
		(pin "P14"
		)
		(pin "P15"
		)
		(pin "P16"
		)
		(pin "P17"
		)
		(pin "P18"
		)
		(pin "P19"
		)
		(pin "P20"
		)
		(pin "P5"
		)
		(pin "P9"
		)
		(pin "R13"
		)
		(pin "R17"
		)
		(pin "R18"
		)
		(pin "R2"
		)
		(pin "R21"
		)
		(pin "R22"
		)
		(pin "R7"
		)
		(pin "R9"
		)
		(pin "T14"
		)
		(pin "T18"
		)
		(pin "T19"
		)
		(pin "T20"
		)
		(pin "T4"
		)
		(pin "T9"
		)
		(pin "U1"
		)
		(pin "U11"
		)
		(pin "U16"
		)
		(pin "U20"
		)
		(pin "U21"
		)
		(pin "U22"
		)
		(pin "U6"
		)
		(pin "V13"
		)
		(pin "V18"
		)
		(pin "V3"
		)
		(pin "V8"
		)
		(pin "W10"
		)
		(pin "W15"
		)
		(pin "W20"
		)
		(pin "W5"
		)
		(pin "Y12"
		)
		(pin "Y17"
		)
		(pin "Y2"
		)
		(pin "Y22"
		)
		(pin "Y7"
		)
		(instances
			(project "polarfire-som"
				(path ""
					(reference "U1")
					(unit 5)
				)
			)
		)
	)
)
